FILE_TYPE = MACRO_DRAWING;
SET COLOR_WIRE YELLOW;
SET COLOR_PROP ORANGE;
SET COLOR_DOT WHITE;
SET COLOR_ARC YELLOW;
SET COLOR_BODY GREEN;
SET COLOR_NOTE PURPLE;
SET PROP_DISPLAY VALUE;
SET PAGE_NUMBER P27;
FORCEADD OFFPAGE..4
R 2
(-6125 4475);
FORCEPROP 2 LAST $XR1 150 
J 0
(-6496 4475);
DISPLAY 0.638298 (-6496 4475);
PAINT MONO (-6496 4475);
FORCEPROP 2 LAST $XR0 27 
J 0
(-6376 4475);
DISPLAY 0.638298 (-6376 4475);
PAINT MONO (-6376 4475);
FORCEPROP 2 LAST CDS_LIB standard
J 2
(-6125 4475);
DISPLAY INVISIBLE (-6125 4475);
FORCEPROP 1 LAST OFFPAGE TRUE
J 2
(-6450 4350);
DISPLAY 0.872340 (-6450 4350);
PAINT GREEN (-6450 4350);
DISPLAY INVISIBLE (-6450 4350);
FORCEPROP 1 LAST COMMENT_BODY TRUE
J 2
(-6100 4375);
DISPLAY 0.872340 (-6100 4375);
PAINT GREEN (-6100 4375);
DISPLAY INVISIBLE (-6100 4375);
FORCEPROP 2 LAST PATH I10
J 2
(-6300 4550);
DISPLAY 1.021277 (-6300 4550);
DISPLAY INVISIBLE (-6300 4550);
FORCEADD UNIVERSAL_POWER..1
(-8675 4825);
FORCEPROP 3 LASTPIN (-8675 4775) SIG_NAME PVDD18_S5_P0\g
J 0
(-8665 4785);
DISPLAY 0.659574 (-8665 4785);
PAINT MONO (-8665 4785);
DISPLAY INVISIBLE (-8665 4785);
FORCEPROP 1 LAST HDL_POWER PVDD18_S5_P0
J 1
(-8675 4875);
DISPLAY 0.489362 (-8675 4875);
PAINT GREEN (-8675 4875);
FORCEPROP 2 LAST CDS_LIB pure_quanta_power
J 0
(-8675 4825);
DISPLAY INVISIBLE (-8675 4825);
FORCEPROP 1 LAST PATH I100
J 0
(-8625 4850);
DISPLAY 0.872340 (-8625 4850);
PAINT AQUA (-8625 4850);
DISPLAY INVISIBLE (-8625 4850);
FORCEADD OFFPAGE..4
R 2
(-6125 4425);
FORCEPROP 2 LAST $XR1 150 
J 0
(-6496 4425);
DISPLAY 0.638298 (-6496 4425);
PAINT MONO (-6496 4425);
FORCEPROP 2 LAST $XR0 27 
J 0
(-6376 4425);
DISPLAY 0.638298 (-6376 4425);
PAINT MONO (-6376 4425);
FORCEPROP 2 LAST CDS_LIB standard
J 0
(-6125 4425);
DISPLAY INVISIBLE (-6125 4425);
FORCEPROP 1 LAST OFFPAGE TRUE
J 2
(-6450 4300);
DISPLAY 0.872340 (-6450 4300);
PAINT GREEN (-6450 4300);
DISPLAY INVISIBLE (-6450 4300);
FORCEPROP 1 LAST COMMENT_BODY TRUE
J 2
(-6100 4325);
DISPLAY 0.872340 (-6100 4325);
PAINT GREEN (-6100 4325);
DISPLAY INVISIBLE (-6100 4325);
FORCEPROP 2 LAST PATH I11
J 0
(-6075 4500);
DISPLAY 1.021277 (-6075 4500);
DISPLAY INVISIBLE (-6075 4500);
FORCEADD OFFPAGE..4
R 2
(-6125 4375);
FORCEPROP 2 LAST $XR1 150 
J 0
(-6496 4375);
DISPLAY 0.638298 (-6496 4375);
PAINT MONO (-6496 4375);
FORCEPROP 2 LAST $XR0 27 
J 0
(-6376 4375);
DISPLAY 0.638298 (-6376 4375);
PAINT MONO (-6376 4375);
FORCEPROP 2 LAST CDS_LIB standard
J 0
(-6125 4375);
DISPLAY INVISIBLE (-6125 4375);
FORCEPROP 1 LAST OFFPAGE TRUE
J 2
(-6450 4250);
DISPLAY 0.872340 (-6450 4250);
PAINT GREEN (-6450 4250);
DISPLAY INVISIBLE (-6450 4250);
FORCEPROP 1 LAST COMMENT_BODY TRUE
J 2
(-6100 4275);
DISPLAY 0.872340 (-6100 4275);
PAINT GREEN (-6100 4275);
DISPLAY INVISIBLE (-6100 4275);
FORCEPROP 2 LAST PATH I12
J 0
(-6075 4450);
DISPLAY 1.021277 (-6075 4450);
DISPLAY INVISIBLE (-6075 4450);
FORCEADD OFFPAGE..4
R 2
(-6125 4275);
FORCEPROP 2 LAST $XR1 150 
J 0
(-6496 4275);
DISPLAY 0.638298 (-6496 4275);
PAINT MONO (-6496 4275);
FORCEPROP 2 LAST $XR0 27 
J 0
(-6376 4275);
DISPLAY 0.638298 (-6376 4275);
PAINT MONO (-6376 4275);
FORCEPROP 2 LAST CDS_LIB standard
J 0
(-6125 4275);
DISPLAY INVISIBLE (-6125 4275);
FORCEPROP 2 LAST PATH I13
J 0
(-6075 4350);
DISPLAY 1.021277 (-6075 4350);
DISPLAY INVISIBLE (-6075 4350);
FORCEPROP 1 LAST COMMENT_BODY TRUE
J 2
(-6100 4175);
DISPLAY 0.872340 (-6100 4175);
PAINT GREEN (-6100 4175);
DISPLAY INVISIBLE (-6100 4175);
FORCEPROP 1 LAST OFFPAGE TRUE
J 2
(-6450 4150);
DISPLAY 0.872340 (-6450 4150);
PAINT GREEN (-6450 4150);
DISPLAY INVISIBLE (-6450 4150);
FORCEADD OFFPAGE..4
R 2
(-6125 4525);
FORCEPROP 2 LAST $XR1 151 
J 0
(-6496 4525);
DISPLAY 0.638298 (-6496 4525);
PAINT MONO (-6496 4525);
FORCEPROP 2 LAST $XR0 27 
J 0
(-6376 4525);
DISPLAY 0.638298 (-6376 4525);
PAINT MONO (-6376 4525);
FORCEPROP 2 LAST CDS_LIB standard
J 0
(-6125 4525);
DISPLAY INVISIBLE (-6125 4525);
FORCEPROP 1 LAST OFFPAGE TRUE
J 2
(-6450 4400);
DISPLAY 0.872340 (-6450 4400);
PAINT GREEN (-6450 4400);
DISPLAY INVISIBLE (-6450 4400);
FORCEPROP 1 LAST COMMENT_BODY TRUE
J 2
(-6100 4425);
DISPLAY 0.872340 (-6100 4425);
PAINT GREEN (-6100 4425);
DISPLAY INVISIBLE (-6100 4425);
FORCEPROP 2 LAST PATH I14
J 0
(-6075 4600);
DISPLAY 1.021277 (-6075 4600);
DISPLAY INVISIBLE (-6075 4600);
FORCEADD OFFPAGE..2
R 2
(-6575 4575);
FORCEPROP 2 LAST $XR1 151 
J 0
(-6919 4575);
DISPLAY 0.638298 (-6919 4575);
PAINT MONO (-6919 4575);
FORCEPROP 2 LAST $XR0 27 
J 0
(-6799 4575);
DISPLAY 0.638298 (-6799 4575);
PAINT MONO (-6799 4575);
FORCEPROP 2 LAST CDS_LIB standard
J 2
(-6575 4575);
DISPLAY INVISIBLE (-6575 4575);
FORCEPROP 1 LAST OFFPAGE TRUE
J 2
(-6900 4450);
DISPLAY 0.872340 (-6900 4450);
PAINT GREEN (-6900 4450);
DISPLAY INVISIBLE (-6900 4450);
FORCEPROP 1 LAST COMMENT_BODY TRUE
J 2
(-6530 4480);
DISPLAY 0.872340 (-6530 4480);
PAINT GREEN (-6530 4480);
DISPLAY INVISIBLE (-6530 4480);
FORCEPROP 2 LAST PATH I169
J 0
(-6775 4625);
DISPLAY 1.021277 (-6775 4625);
DISPLAY INVISIBLE (-6775 4625);
FORCEADD Q_RES..1
R 2
(-5725 4575);
FORCEPROP 1 LAST LOCATION R404
J 2
(-5825 4575);
DISPLAY 0.489362 (-5825 4575);
PAINT SKYBLUE (-5825 4575);
FORCEPROP 0 LAST $SEC 1
J 0
(-5825 4625);
DISPLAY 0.680851 (-5825 4625);
PAINT MONO (-5825 4625);
DISPLAY INVISIBLE (-5825 4625);
FORCEPROP 0 LAST CDS_SEC 1
J 0
(-5825 4625);
DISPLAY 1.021277 (-5825 4625);
DISPLAY INVISIBLE (-5825 4625);
FORCEPROP 1 LASTPIN (-5625 4575) $PN 1
J 2
(-5637 4587);
DISPLAY 0.489362 (-5637 4587);
PAINT MONO (-5637 4587);
FORCEPROP 1 LASTPIN (-5825 4575) $PN 2
J 2
(-5787 4587);
DISPLAY 0.489362 (-5787 4587);
PAINT MONO (-5787 4587);
FORCEPROP 1 LAST VALUE 0
J 0
(-5625 4575);
DISPLAY 0.489362 (-5625 4575);
PAINT SKYBLUE (-5625 4575);
FORCEPROP 2 LAST CDS_LIB pure_quanta
J 0
(-5725 4575);
DISPLAY INVISIBLE (-5725 4575);
FORCEPROP 1 LAST PATH I170
J 2
(-5675 4725);
DISPLAY 0.978723 (-5675 4725);
PAINT WHITE (-5675 4725);
DISPLAY INVISIBLE (-5675 4725);
FORCEPROP 1 LAST WATTAGE 1/16W
J 0
(-6125 4500);
DISPLAY 0.489362 (-6125 4500);
PAINT SKYBLUE (-6125 4500);
DISPLAY INVISIBLE (-6125 4500);
FORCEPROP 1 LAST MATERIAL CHIP
J 2
(-6150 4500);
DISPLAY 0.489362 (-6150 4500);
PAINT SKYBLUE (-6150 4500);
DISPLAY INVISIBLE (-6150 4500);
FORCEPROP 1 LAST TOLERANCE 5%
J 2
(-5700 4500);
DISPLAY 0.489362 (-5700 4500);
PAINT SKYBLUE (-5700 4500);
DISPLAY INVISIBLE (-5700 4500);
FORCEPROP 1 LAST PART_NUMBER CS00002JB38
J 2
(-5750 4625);
DISPLAY 0.489362 (-5750 4625);
PAINT SKYBLUE (-5750 4625);
DISPLAY INVISIBLE (-5750 4625);
FORCEPROP 1 LAST PACK_TYPE 0402LF
J 2
(-5775 4500);
DISPLAY 0.489362 (-5775 4500);
PAINT SKYBLUE (-5775 4500);
DISPLAY INVISIBLE (-5775 4500);
FORCEADD OFFPAGE..2
R 2
(-6125 2425);
FORCEPROP 2 LAST $XR1 81 
J 0
(-6439 2425);
DISPLAY 0.638298 (-6439 2425);
PAINT MONO (-6439 2425);
FORCEPROP 2 LAST $XR0 27 
J 0
(-6349 2425);
DISPLAY 0.638298 (-6349 2425);
PAINT MONO (-6349 2425);
FORCEPROP 2 LAST CDS_LIB standard
J 0
(-6125 2425);
DISPLAY INVISIBLE (-6125 2425);
FORCEPROP 1 LAST OFFPAGE TRUE
J 2
(-6450 2300);
DISPLAY 0.872340 (-6450 2300);
PAINT GREEN (-6450 2300);
DISPLAY INVISIBLE (-6450 2300);
FORCEPROP 1 LAST COMMENT_BODY TRUE
J 2
(-6080 2330);
DISPLAY 0.872340 (-6080 2330);
PAINT GREEN (-6080 2330);
DISPLAY INVISIBLE (-6080 2330);
FORCEPROP 2 LAST PATH I191
J 0
(-6325 2475);
DISPLAY 1.021277 (-6325 2475);
DISPLAY INVISIBLE (-6325 2475);
FORCEADD GENOA_SP5..20
(-4275 3500);
FORCEPROP 1 LAST LOCATION U25
J 0
(-4870 6231);
DISPLAY 0.489362 (-4870 6231);
PAINT SKYBLUE (-4870 6231);
FORCEPROP 0 LAST $SEC 20
J 0
(-4850 6375);
DISPLAY 0.680851 (-4850 6375);
PAINT MONO (-4850 6375);
DISPLAY INVISIBLE (-4850 6375);
FORCEPROP 0 LAST CDS_SEC 20
J 0
(-4850 6375);
DISPLAY 1.021277 (-4850 6375);
DISPLAY INVISIBLE (-4850 6375);
FORCEPROP 0 LASTPIN (-3525 4875) $PN A68
J 0
(-3515 4885);
DISPLAY 0.489362 (-3515 4885);
PAINT MONO (-3515 4885);
FORCEPROP 0 LASTPIN (-3525 5775) $PN C32
J 0
(-3515 5785);
DISPLAY 0.489362 (-3515 5785);
PAINT MONO (-3515 5785);
FORCEPROP 0 LASTPIN (-3525 5725) $PN A34
J 0
(-3515 5735);
DISPLAY 0.489362 (-3515 5735);
PAINT MONO (-3515 5735);
FORCEPROP 0 LASTPIN (-3525 5675) $PN C33
J 0
(-3515 5685);
DISPLAY 0.489362 (-3515 5685);
PAINT MONO (-3515 5685);
FORCEPROP 0 LASTPIN (-3525 5625) $PN D33
J 0
(-3515 5635);
DISPLAY 0.489362 (-3515 5635);
PAINT MONO (-3515 5635);
FORCEPROP 0 LASTPIN (-3525 5575) $PN A33
J 0
(-3515 5585);
DISPLAY 0.489362 (-3515 5585);
PAINT MONO (-3515 5585);
FORCEPROP 0 LASTPIN (-3525 5525) $PN A32
J 0
(-3515 5535);
DISPLAY 0.489362 (-3515 5535);
PAINT MONO (-3515 5535);
FORCEPROP 0 LASTPIN (-3525 5475) $PN D32
J 0
(-3515 5485);
DISPLAY 0.489362 (-3515 5485);
PAINT MONO (-3515 5485);
FORCEPROP 0 LASTPIN (-3525 4225) $PN C63
J 0
(-3515 4235);
DISPLAY 0.489362 (-3515 4235);
PAINT MONO (-3515 4235);
FORCEPROP 0 LASTPIN (-3525 4175) $PN C62
J 0
(-3515 4185);
DISPLAY 0.489362 (-3515 4185);
PAINT MONO (-3515 4185);
FORCEPROP 0 LASTPIN (-3525 4125) $PN A63
J 0
(-3515 4135);
DISPLAY 0.489362 (-3515 4135);
PAINT MONO (-3515 4135);
FORCEPROP 0 LASTPIN (-3525 4075) $PN A62
J 0
(-3515 4085);
DISPLAY 0.489362 (-3515 4085);
PAINT MONO (-3515 4085);
FORCEPROP 0 LASTPIN (-5025 2525) $PN C70
J 2
(-5035 2535);
DISPLAY 0.489362 (-5035 2535);
PAINT MONO (-5035 2535);
FORCEPROP 0 LASTPIN (-5025 2475) $PN B69
J 2
(-5035 2485);
DISPLAY 0.489362 (-5035 2485);
PAINT MONO (-5035 2485);
FORCEPROP 0 LASTPIN (-5025 2425) $PN D68
J 2
(-5035 2435);
DISPLAY 0.489362 (-5035 2435);
PAINT MONO (-5035 2435);
FORCEPROP 0 LASTPIN (-5025 3075) $PN B66
J 2
(-5035 3085);
DISPLAY 0.489362 (-5035 3085);
PAINT MONO (-5035 3085);
FORCEPROP 0 LASTPIN (-5025 4275) $PN C16
J 2
(-5035 4285);
DISPLAY 0.489362 (-5035 4285);
PAINT MONO (-5035 4285);
FORCEPROP 0 LASTPIN (-5025 5675) $PN C22
J 2
(-5035 5685);
DISPLAY 0.489362 (-5035 5685);
PAINT MONO (-5035 5685);
FORCEPROP 0 LASTPIN (-5025 5625) $PN DG72
J 2
(-5035 5635);
DISPLAY 0.489362 (-5035 5635);
PAINT MONO (-5035 5635);
FORCEPROP 0 LASTPIN (-3525 4775) $PN A69
J 0
(-3515 4785);
DISPLAY 0.489362 (-3515 4785);
PAINT MONO (-3515 4785);
FORCEPROP 0 LASTPIN (-5025 1125) $PN DH8
J 2
(-5035 1135);
DISPLAY 0.489362 (-5035 1135);
PAINT MONO (-5035 1135);
FORCEPROP 0 LASTPIN (-5025 2975) $PN DJ55
J 2
(-5035 2985);
DISPLAY 0.489362 (-5035 2985);
PAINT MONO (-5035 2985);
FORCEPROP 0 LASTPIN (-5025 2925) $PN DJ56
J 2
(-5035 2935);
DISPLAY 0.489362 (-5035 2935);
PAINT MONO (-5035 2935);
FORCEPROP 0 LASTPIN (-5025 4875) $PN DJ71
J 2
(-5035 4885);
DISPLAY 0.489362 (-5035 4885);
PAINT MONO (-5035 4885);
FORCEPROP 0 LASTPIN (-5025 4825) $PN DH71
J 2
(-5035 4835);
DISPLAY 0.489362 (-5035 4835);
PAINT MONO (-5035 4835);
FORCEPROP 0 LASTPIN (-5025 2775) $PN C19
J 2
(-5035 2785);
DISPLAY 0.489362 (-5035 2785);
PAINT MONO (-5035 2785);
FORCEPROP 0 LASTPIN (-5025 2725) $PN C68
J 2
(-5035 2735);
DISPLAY 0.489362 (-5035 2735);
PAINT MONO (-5035 2735);
FORCEPROP 0 LASTPIN (-5025 2675) $PN DH73
J 2
(-5035 2685);
DISPLAY 0.489362 (-5035 2685);
PAINT MONO (-5035 2685);
FORCEPROP 0 LASTPIN (-5025 2625) $PN DH10
J 2
(-5035 2635);
DISPLAY 0.489362 (-5035 2635);
PAINT MONO (-5035 2635);
FORCEPROP 0 LASTPIN (-5025 5525) $PN A23
J 2
(-5035 5535);
DISPLAY 0.489362 (-5035 5535);
PAINT MONO (-5035 5535);
FORCEPROP 0 LASTPIN (-5025 5325) $PN DJ72
J 2
(-5035 5335);
DISPLAY 0.489362 (-5035 5335);
PAINT MONO (-5035 5335);
FORCEPROP 0 LASTPIN (-5025 5475) $PN A22
J 2
(-5035 5485);
DISPLAY 0.489362 (-5035 5485);
PAINT MONO (-5035 5485);
FORCEPROP 0 LASTPIN (-5025 5275) $PN DH72
J 2
(-5035 5285);
DISPLAY 0.489362 (-5035 5285);
PAINT MONO (-5035 5285);
FORCEPROP 0 LASTPIN (-5025 5425) $PN B21
J 2
(-5035 5435);
DISPLAY 0.489362 (-5035 5435);
PAINT MONO (-5035 5435);
FORCEPROP 0 LASTPIN (-5025 5225) $PN DG73
J 2
(-5035 5235);
DISPLAY 0.489362 (-5035 5235);
PAINT MONO (-5035 5235);
FORCEPROP 0 LASTPIN (-5025 4425) $PN B17
J 2
(-5035 4435);
DISPLAY 0.489362 (-5035 4435);
PAINT MONO (-5035 4435);
FORCEPROP 0 LASTPIN (-5025 4525) $PN C17
J 2
(-5035 4535);
DISPLAY 0.489362 (-5035 4535);
PAINT MONO (-5035 4535);
FORCEPROP 0 LASTPIN (-5025 4575) $PN C18
J 2
(-5035 4585);
DISPLAY 0.489362 (-5035 4585);
PAINT MONO (-5035 4585);
FORCEPROP 0 LASTPIN (-3525 3125) $PN AA50
J 0
(-3515 3135);
DISPLAY 0.489362 (-3515 3135);
PAINT MONO (-3515 3135);
FORCEPROP 0 LASTPIN (-3525 3075) $PN CJ28
J 0
(-3515 3085);
DISPLAY 0.489362 (-3515 3085);
PAINT MONO (-3515 3085);
FORCEPROP 0 LASTPIN (-3525 3025) $PN CJ48
J 0
(-3515 3035);
DISPLAY 0.489362 (-3515 3035);
PAINT MONO (-3515 3035);
FORCEPROP 0 LASTPIN (-3525 2975) $PN AA30
J 0
(-3515 2985);
DISPLAY 0.489362 (-3515 2985);
PAINT MONO (-3515 2985);
FORCEPROP 0 LASTPIN (-3525 2925) $PN AA52
J 0
(-3515 2935);
DISPLAY 0.489362 (-3515 2935);
PAINT MONO (-3515 2935);
FORCEPROP 0 LASTPIN (-3525 2875) $PN CJ26
J 0
(-3515 2885);
DISPLAY 0.489362 (-3515 2885);
PAINT MONO (-3515 2885);
FORCEPROP 0 LASTPIN (-3525 2825) $PN CJ50
J 0
(-3515 2835);
DISPLAY 0.489362 (-3515 2835);
PAINT MONO (-3515 2835);
FORCEPROP 0 LASTPIN (-3525 2775) $PN AA27
J 0
(-3515 2785);
DISPLAY 0.489362 (-3515 2785);
PAINT MONO (-3515 2785);
FORCEPROP 0 LASTPIN (-3525 2725) $PN AA48
J 0
(-3515 2735);
DISPLAY 0.489362 (-3515 2735);
PAINT MONO (-3515 2735);
FORCEPROP 0 LASTPIN (-3525 2675) $PN CK30
J 0
(-3515 2685);
DISPLAY 0.489362 (-3515 2685);
PAINT MONO (-3515 2685);
FORCEPROP 0 LASTPIN (-3525 2625) $PN CJ47
J 0
(-3515 2635);
DISPLAY 0.489362 (-3515 2635);
PAINT MONO (-3515 2635);
FORCEPROP 0 LASTPIN (-3525 2575) $PN AA28
J 0
(-3515 2585);
DISPLAY 0.489362 (-3515 2585);
PAINT MONO (-3515 2585);
FORCEPROP 0 LASTPIN (-3525 1825) $PN AA25
J 0
(-3515 1835);
DISPLAY 0.489362 (-3515 1835);
PAINT MONO (-3515 1835);
FORCEPROP 0 LASTPIN (-3525 2475) $PN AA51
J 0
(-3515 2485);
DISPLAY 0.489362 (-3515 2485);
PAINT MONO (-3515 2485);
FORCEPROP 0 LASTPIN (-3525 2425) $PN CJ27
J 0
(-3515 2435);
DISPLAY 0.489362 (-3515 2435);
PAINT MONO (-3515 2435);
FORCEPROP 0 LASTPIN (-3525 2375) $PN CJ49
J 0
(-3515 2385);
DISPLAY 0.489362 (-3515 2385);
PAINT MONO (-3515 2385);
FORCEPROP 0 LASTPIN (-3525 2325) $PN Y30
J 0
(-3515 2335);
DISPLAY 0.489362 (-3515 2335);
PAINT MONO (-3515 2335);
FORCEPROP 0 LASTPIN (-3525 2275) $PN AA53
J 0
(-3515 2285);
DISPLAY 0.489362 (-3515 2285);
PAINT MONO (-3515 2285);
FORCEPROP 0 LASTPIN (-3525 2225) $PN CJ25
J 0
(-3515 2235);
DISPLAY 0.489362 (-3515 2235);
PAINT MONO (-3515 2235);
FORCEPROP 0 LASTPIN (-3525 2175) $PN CJ51
J 0
(-3515 2185);
DISPLAY 0.489362 (-3515 2185);
PAINT MONO (-3515 2185);
FORCEPROP 0 LASTPIN (-3525 2125) $PN AA26
J 0
(-3515 2135);
DISPLAY 0.489362 (-3515 2135);
PAINT MONO (-3515 2135);
FORCEPROP 0 LASTPIN (-3525 2075) $PN Y47
J 0
(-3515 2085);
DISPLAY 0.489362 (-3515 2085);
PAINT MONO (-3515 2085);
FORCEPROP 0 LASTPIN (-3525 2025) $PN CK29
J 0
(-3515 2035);
DISPLAY 0.489362 (-3515 2035);
PAINT MONO (-3515 2035);
FORCEPROP 0 LASTPIN (-3525 1975) $PN CK47
J 0
(-3515 1985);
DISPLAY 0.489362 (-3515 1985);
PAINT MONO (-3515 1985);
FORCEPROP 0 LASTPIN (-3525 1925) $PN Y29
J 0
(-3515 1935);
DISPLAY 0.489362 (-3515 1935);
PAINT MONO (-3515 1935);
FORCEPROP 0 LASTPIN (-3525 1725) $PN AA24
J 0
(-3515 1735);
DISPLAY 0.489362 (-3515 1735);
PAINT MONO (-3515 1735);
FORCEPROP 0 LASTPIN (-3525 3875) $PN AA46
J 0
(-3515 3885);
DISPLAY 0.489362 (-3515 3885);
PAINT MONO (-3515 3885);
FORCEPROP 0 LASTPIN (-3525 3825) $PN CJ30
J 0
(-3515 3835);
DISPLAY 0.489362 (-3515 3835);
PAINT MONO (-3515 3835);
FORCEPROP 0 LASTPIN (-3525 3775) $PN CJ46
J 0
(-3515 3785);
DISPLAY 0.489362 (-3515 3785);
PAINT MONO (-3515 3785);
FORCEPROP 0 LASTPIN (-3525 3725) $PN Y46
J 0
(-3515 3735);
DISPLAY 0.489362 (-3515 3735);
PAINT MONO (-3515 3735);
FORCEPROP 0 LASTPIN (-3525 3225) $PN AA49
J 0
(-3515 3235);
DISPLAY 0.489362 (-3515 3235);
PAINT MONO (-3515 3235);
FORCEPROP 0 LASTPIN (-3525 3575) $PN AA47
J 0
(-3515 3585);
DISPLAY 0.489362 (-3515 3585);
PAINT MONO (-3515 3585);
FORCEPROP 0 LASTPIN (-3525 3525) $PN CJ29
J 0
(-3515 3535);
DISPLAY 0.489362 (-3515 3535);
PAINT MONO (-3515 3535);
FORCEPROP 0 LASTPIN (-3525 3475) $PN AA29
J 0
(-3515 3485);
DISPLAY 0.489362 (-3515 3485);
PAINT MONO (-3515 3485);
FORCEPROP 0 LASTPIN (-3525 3425) $PN CJ52
J 0
(-3515 3435);
DISPLAY 0.489362 (-3515 3435);
PAINT MONO (-3515 3435);
FORCEPROP 0 LASTPIN (-3525 3375) $PN AA23
J 0
(-3515 3385);
DISPLAY 0.489362 (-3515 3385);
PAINT MONO (-3515 3385);
FORCEPROP 0 LASTPIN (-3525 3325) $PN CJ53
J 0
(-3515 3335);
DISPLAY 0.489362 (-3515 3335);
PAINT MONO (-3515 3335);
FORCEPROP 0 LASTPIN (-3525 1125) $PN W31
J 0
(-3515 1135);
DISPLAY 0.489362 (-3515 1135);
PAINT MONO (-3515 1135);
FORCEPROP 0 LASTPIN (-5025 3825) $PN B60
J 2
(-5035 3835);
DISPLAY 0.489362 (-5035 3835);
PAINT MONO (-5035 3835);
FORCEPROP 0 LASTPIN (-5025 3775) $PN CJ24
J 2
(-5035 3785);
DISPLAY 0.489362 (-5035 3785);
PAINT MONO (-5035 3785);
FORCEPROP 0 LASTPIN (-5025 3725) $PN CK46
J 2
(-5035 3735);
DISPLAY 0.489362 (-5035 3735);
PAINT MONO (-5035 3735);
FORCEPROP 0 LASTPIN (-5025 3675) $PN E32
J 2
(-5035 3685);
DISPLAY 0.489362 (-5035 3685);
PAINT MONO (-5035 3685);
FORCEPROP 0 LASTPIN (-5025 3575) $PN B58
J 2
(-5035 3585);
DISPLAY 0.489362 (-5035 3585);
PAINT MONO (-5035 3585);
FORCEPROP 0 LASTPIN (-5025 3525) $PN D7
J 2
(-5035 3535);
DISPLAY 0.489362 (-5035 3535);
PAINT MONO (-5035 3535);
FORCEPROP 0 LASTPIN (-5025 3225) $PN B61
J 2
(-5035 3235);
DISPLAY 0.489362 (-5035 3235);
PAINT MONO (-5035 3235);
FORCEPROP 0 LASTPIN (-3525 4725) $PN DJ9
J 0
(-3515 4735);
DISPLAY 0.489362 (-3515 4735);
PAINT MONO (-3515 4735);
FORCEPROP 0 LASTPIN (-5025 4375) $PN A16
J 2
(-5035 4385);
DISPLAY 0.489362 (-5035 4385);
PAINT MONO (-5035 4385);
FORCEPROP 0 LASTPIN (-5025 4475) $PN A17
J 2
(-5035 4485);
DISPLAY 0.489362 (-5035 4485);
PAINT MONO (-5035 4485);
FORCEPROP 0 LASTPIN (-3525 1625) $PN DJ33
J 0
(-3515 1635);
DISPLAY 0.489362 (-3515 1635);
PAINT MONO (-3515 1635);
FORCEPROP 0 LASTPIN (-3525 1525) $PN DG34
J 0
(-3515 1535);
DISPLAY 0.489362 (-3515 1535);
PAINT MONO (-3515 1535);
FORCEPROP 0 LASTPIN (-3525 1575) $PN DF34
J 0
(-3515 1585);
DISPLAY 0.489362 (-3515 1585);
PAINT MONO (-3515 1585);
FORCEPROP 0 LASTPIN (-3525 1425) $PN DG35
J 0
(-3515 1435);
DISPLAY 0.489362 (-3515 1435);
PAINT MONO (-3515 1435);
FORCEPROP 0 LASTPIN (-3525 1475) $PN DJ34
J 0
(-3515 1485);
DISPLAY 0.489362 (-3515 1485);
PAINT MONO (-3515 1485);
FORCEPROP 0 LASTPIN (-3525 1325) $PN DH33
J 0
(-3515 1335);
DISPLAY 0.489362 (-3515 1335);
PAINT MONO (-3515 1335);
FORCEPROP 0 LASTPIN (-3525 1375) $PN DJ32
J 0
(-3515 1385);
DISPLAY 0.489362 (-3515 1385);
PAINT MONO (-3515 1385);
FORCEPROP 0 LASTPIN (-5025 1925) $PN DH3
J 2
(-5035 1935);
DISPLAY 0.489362 (-5035 1935);
PAINT MONO (-5035 1935);
FORCEPROP 0 LASTPIN (-5025 1825) $PN C74
J 2
(-5035 1835);
DISPLAY 0.489362 (-5035 1835);
PAINT MONO (-5035 1835);
FORCEPROP 0 LASTPIN (-5025 1875) $PN BP53
J 2
(-5035 1885);
DISPLAY 0.489362 (-5035 1885);
PAINT MONO (-5035 1885);
FORCEPROP 0 LASTPIN (-5025 1975) $PN C2
J 2
(-5035 1985);
DISPLAY 0.489362 (-5035 1985);
PAINT MONO (-5035 1985);
FORCEPROP 0 LASTPIN (-5025 2025) $PN DG3
J 2
(-5035 2035);
DISPLAY 0.489362 (-5035 2035);
PAINT MONO (-5035 2035);
FORCEPROP 0 LASTPIN (-5025 1775) $PN B3
J 2
(-5035 1785);
DISPLAY 0.489362 (-5035 1785);
PAINT MONO (-5035 1785);
FORCEPROP 0 LASTPIN (-5025 2075) $PN BR53
J 2
(-5035 2085);
DISPLAY 0.489362 (-5035 2085);
PAINT MONO (-5035 2085);
FORCEPROP 0 LASTPIN (-5025 2325) $PN C3
J 2
(-5035 2335);
DISPLAY 0.489362 (-5035 2335);
PAINT MONO (-5035 2335);
FORCEPROP 0 LASTPIN (-5025 2275) $PN BR54
J 2
(-5035 2285);
DISPLAY 0.489362 (-5035 2285);
PAINT MONO (-5035 2285);
FORCEPROP 0 LASTPIN (-5025 2225) $PN DJ3
J 2
(-5035 2235);
DISPLAY 0.489362 (-5035 2235);
PAINT MONO (-5035 2235);
FORCEPROP 0 LASTPIN (-5025 2175) $PN B73
J 2
(-5035 2185);
DISPLAY 0.489362 (-5035 2185);
PAINT MONO (-5035 2185);
FORCEPROP 0 LASTPIN (-3525 4575) $PN C66
J 0
(-3515 4585);
DISPLAY 0.489362 (-3515 4585);
PAINT MONO (-3515 4585);
FORCEPROP 0 LASTPIN (-3525 4525) $PN C65
J 0
(-3515 4535);
DISPLAY 0.489362 (-3515 4535);
PAINT MONO (-3515 4535);
FORCEPROP 0 LASTPIN (-3525 4475) $PN A66
J 0
(-3515 4485);
DISPLAY 0.489362 (-3515 4485);
PAINT MONO (-3515 4485);
FORCEPROP 0 LASTPIN (-3525 4425) $PN A65
J 0
(-3515 4435);
DISPLAY 0.489362 (-3515 4435);
PAINT MONO (-3515 4435);
FORCEPROP 2 LAST PART_TYPE SMLF
J 0
(-4850 6325);
DISPLAY 1.021277 (-4850 6325);
FORCEPROP 1 LAST MATERIAL IO
J 0
(-4870 5957);
DISPLAY 0.489362 (-4870 5957);
PAINT SKYBLUE (-4870 5957);
FORCEPROP 2 LAST VALUE SOCKET6096_13568-001
J 0
(-4850 6275);
DISPLAY 0.489362 (-4850 6275);
PAINT SKYBLUE (-4850 6275);
FORCEPROP 1 LAST PART_NUMBER DGA^6000030
J 0
(-4870 6084);
DISPLAY 0.489362 (-4870 6084);
PAINT SKYBLUE (-4870 6084);
FORCEPROP 2 LAST CDS_LIB pure_quanta
J 0
(-4275 3500);
DISPLAY INVISIBLE (-4275 3500);
FORCEPROP 1 LAST CDS_LMAN_SYM_OUTLINE -600,2425,600,-2425
J 0
(-4275 3500);
DISPLAY 0.468085 (-4275 3500);
PAINT GREEN (-4275 3500);
DISPLAY INVISIBLE (-4275 3500);
FORCEPROP 1 LAST NEEDS_NO_SIZE TRUE
J 0
(-4275 3500);
DISPLAY 0.723404 (-4275 3500);
PAINT GREEN (-4275 3500);
DISPLAY INVISIBLE (-4275 3500);
FORCEPROP 1 LAST PATH I227
J 0
(-4275 3500);
DISPLAY 0.723404 (-4275 3500);
PAINT GREEN (-4275 3500);
DISPLAY INVISIBLE (-4275 3500);
FORCEADD UNIVERSAL_POWER..1
(-225 5925);
FORCEPROP 3 LASTPIN (-225 5875) SIG_NAME PVDD18_S5_P0\g
J 0
(-215 5885);
DISPLAY 0.659574 (-215 5885);
PAINT MONO (-215 5885);
DISPLAY INVISIBLE (-215 5885);
FORCEPROP 1 LAST HDL_POWER PVDD18_S5_P0
J 1
(-225 5975);
DISPLAY 0.489362 (-225 5975);
PAINT GREEN (-225 5975);
FORCEPROP 2 LAST CDS_LIB pure_quanta_power
J 0
(-225 5925);
DISPLAY INVISIBLE (-225 5925);
FORCEPROP 1 LAST PATH I231
J 0
(-175 5950);
DISPLAY 0.872340 (-175 5950);
PAINT AQUA (-175 5950);
DISPLAY INVISIBLE (-175 5950);
FORCEADD OFFPAGE..2
R 2
(-1525 5550);
FORCEPROP 2 LAST $XR0 27 
J 0
(-1779 5550);
DISPLAY 0.638298 (-1779 5550);
PAINT MONO (-1779 5550);
FORCEPROP 2 LAST CDS_LIB standard
J 0
(-1525 5550);
DISPLAY INVISIBLE (-1525 5550);
FORCEPROP 1 LAST OFFPAGE TRUE
J 2
(-1850 5425);
DISPLAY 0.872340 (-1850 5425);
PAINT GREEN (-1850 5425);
DISPLAY INVISIBLE (-1850 5425);
FORCEPROP 1 LAST COMMENT_BODY TRUE
J 2
(-1480 5455);
DISPLAY 0.872340 (-1480 5455);
PAINT PEACH (-1480 5455);
DISPLAY INVISIBLE (-1480 5455);
FORCEPROP 2 LAST PATH I245
J 0
(-1725 5600);
DISPLAY 1.021277 (-1725 5600);
DISPLAY INVISIBLE (-1725 5600);
FORCEADD OFFPAGE..2
R 2
(-1525 5600);
FORCEPROP 2 LAST $XR0 27 
J 0
(-1779 5600);
DISPLAY 0.638298 (-1779 5600);
PAINT MONO (-1779 5600);
FORCEPROP 2 LAST CDS_LIB standard
J 0
(-1525 5600);
DISPLAY INVISIBLE (-1525 5600);
FORCEPROP 1 LAST OFFPAGE TRUE
J 2
(-1850 5475);
DISPLAY 0.872340 (-1850 5475);
PAINT GREEN (-1850 5475);
DISPLAY INVISIBLE (-1850 5475);
FORCEPROP 1 LAST COMMENT_BODY TRUE
J 2
(-1480 5505);
DISPLAY 0.872340 (-1480 5505);
PAINT PEACH (-1480 5505);
DISPLAY INVISIBLE (-1480 5505);
FORCEPROP 2 LAST PATH I246
J 0
(-1725 5650);
DISPLAY 1.021277 (-1725 5650);
DISPLAY INVISIBLE (-1725 5650);
FORCEADD OFFPAGE..2
R 2
(-1525 5500);
FORCEPROP 2 LAST $XR0 27 
J 0
(-1779 5500);
DISPLAY 0.638298 (-1779 5500);
PAINT MONO (-1779 5500);
FORCEPROP 2 LAST CDS_LIB standard
J 0
(-1525 5500);
DISPLAY INVISIBLE (-1525 5500);
FORCEPROP 1 LAST OFFPAGE TRUE
J 2
(-1850 5375);
DISPLAY 0.872340 (-1850 5375);
PAINT GREEN (-1850 5375);
DISPLAY INVISIBLE (-1850 5375);
FORCEPROP 1 LAST COMMENT_BODY TRUE
J 2
(-1480 5405);
DISPLAY 0.872340 (-1480 5405);
PAINT PEACH (-1480 5405);
DISPLAY INVISIBLE (-1480 5405);
FORCEPROP 2 LAST PATH I247
J 0
(-1725 5550);
DISPLAY 1.021277 (-1725 5550);
DISPLAY INVISIBLE (-1725 5550);
FORCEADD OFFPAGE..2
R 2
(-1525 5450);
FORCEPROP 2 LAST $XR0 27 
J 0
(-1779 5450);
DISPLAY 0.638298 (-1779 5450);
PAINT MONO (-1779 5450);
FORCEPROP 2 LAST CDS_LIB standard
J 0
(-1525 5450);
DISPLAY INVISIBLE (-1525 5450);
FORCEPROP 1 LAST OFFPAGE TRUE
J 2
(-1850 5325);
DISPLAY 0.872340 (-1850 5325);
PAINT GREEN (-1850 5325);
DISPLAY INVISIBLE (-1850 5325);
FORCEPROP 1 LAST COMMENT_BODY TRUE
J 2
(-1480 5355);
DISPLAY 0.872340 (-1480 5355);
PAINT PEACH (-1480 5355);
DISPLAY INVISIBLE (-1480 5355);
FORCEPROP 2 LAST PATH I248
J 0
(-1725 5500);
DISPLAY 1.021277 (-1725 5500);
DISPLAY INVISIBLE (-1725 5500);
FORCEADD OFFPAGE..2
R 2
(-1525 5400);
FORCEPROP 2 LAST $XR1 27 
J 0
(-1869 5400);
DISPLAY 0.638298 (-1869 5400);
PAINT MONO (-1869 5400);
FORCEPROP 2 LAST $XR0 81 
J 0
(-1779 5400);
DISPLAY 0.638298 (-1779 5400);
PAINT MONO (-1779 5400);
FORCEPROP 2 LAST CDS_LIB standard
J 0
(-1525 5400);
DISPLAY INVISIBLE (-1525 5400);
FORCEPROP 1 LAST OFFPAGE TRUE
J 2
(-1850 5275);
DISPLAY 0.872340 (-1850 5275);
PAINT GREEN (-1850 5275);
DISPLAY INVISIBLE (-1850 5275);
FORCEPROP 1 LAST COMMENT_BODY TRUE
J 2
(-1480 5305);
DISPLAY 0.872340 (-1480 5305);
PAINT PEACH (-1480 5305);
DISPLAY INVISIBLE (-1480 5305);
FORCEPROP 2 LAST PATH I249
J 0
(-1725 5450);
DISPLAY 1.021277 (-1725 5450);
DISPLAY INVISIBLE (-1725 5450);
FORCEADD OFFPAGE..2
R 2
(-1525 5300);
FORCEPROP 2 LAST $XR2 149 
J 0
(-1989 5300);
DISPLAY 0.638298 (-1989 5300);
PAINT MONO (-1989 5300);
FORCEPROP 2 LAST $XR1 81 
J 0
(-1869 5300);
DISPLAY 0.638298 (-1869 5300);
PAINT MONO (-1869 5300);
FORCEPROP 2 LAST $XR0 27 
J 0
(-1779 5300);
DISPLAY 0.638298 (-1779 5300);
PAINT MONO (-1779 5300);
FORCEPROP 2 LAST CDS_LIB standard
J 0
(-1525 5300);
DISPLAY INVISIBLE (-1525 5300);
FORCEPROP 1 LAST OFFPAGE TRUE
J 2
(-1850 5175);
DISPLAY 0.872340 (-1850 5175);
PAINT GREEN (-1850 5175);
DISPLAY INVISIBLE (-1850 5175);
FORCEPROP 1 LAST COMMENT_BODY TRUE
J 2
(-1480 5205);
DISPLAY 0.872340 (-1480 5205);
PAINT PEACH (-1480 5205);
DISPLAY INVISIBLE (-1480 5205);
FORCEPROP 2 LAST PATH I250
J 0
(-1725 5350);
DISPLAY 1.021277 (-1725 5350);
DISPLAY INVISIBLE (-1725 5350);
FORCEADD OFFPAGE..2
R 2
(-1525 5350);
FORCEPROP 2 LAST $XR1 81 
J 0
(-1869 5350);
DISPLAY 0.638298 (-1869 5350);
PAINT MONO (-1869 5350);
FORCEPROP 2 LAST $XR0 27 
J 0
(-1779 5350);
DISPLAY 0.638298 (-1779 5350);
PAINT MONO (-1779 5350);
FORCEPROP 2 LAST CDS_LIB standard
J 0
(-1525 5350);
DISPLAY INVISIBLE (-1525 5350);
FORCEPROP 1 LAST OFFPAGE TRUE
J 2
(-1850 5225);
DISPLAY 0.872340 (-1850 5225);
PAINT GREEN (-1850 5225);
DISPLAY INVISIBLE (-1850 5225);
FORCEPROP 1 LAST COMMENT_BODY TRUE
J 2
(-1480 5255);
DISPLAY 0.872340 (-1480 5255);
PAINT PEACH (-1480 5255);
DISPLAY INVISIBLE (-1480 5255);
FORCEPROP 2 LAST PATH I251
J 0
(-1725 5400);
DISPLAY 1.021277 (-1725 5400);
DISPLAY INVISIBLE (-1725 5400);
FORCEADD OFFPAGE..2
R 2
(-1525 5250);
FORCEPROP 2 LAST $XR2 149 
J 0
(-1989 5250);
DISPLAY 0.638298 (-1989 5250);
PAINT MONO (-1989 5250);
FORCEPROP 2 LAST $XR1 81 
J 0
(-1869 5250);
DISPLAY 0.638298 (-1869 5250);
PAINT MONO (-1869 5250);
FORCEPROP 2 LAST $XR0 27 
J 0
(-1779 5250);
DISPLAY 0.638298 (-1779 5250);
PAINT MONO (-1779 5250);
FORCEPROP 2 LAST CDS_LIB standard
J 0
(-1525 5250);
DISPLAY INVISIBLE (-1525 5250);
FORCEPROP 1 LAST OFFPAGE TRUE
J 2
(-1850 5125);
DISPLAY 0.872340 (-1850 5125);
PAINT GREEN (-1850 5125);
DISPLAY INVISIBLE (-1850 5125);
FORCEPROP 1 LAST COMMENT_BODY TRUE
J 2
(-1480 5155);
DISPLAY 0.872340 (-1480 5155);
PAINT PEACH (-1480 5155);
DISPLAY INVISIBLE (-1480 5155);
FORCEPROP 2 LAST PATH I252
J 0
(-1725 5300);
DISPLAY 1.021277 (-1725 5300);
DISPLAY INVISIBLE (-1725 5300);
FORCEADD OFFPAGE..2
R 2
(-1525 5200);
FORCEPROP 2 LAST $XR2 149 
J 0
(-1989 5200);
DISPLAY 0.638298 (-1989 5200);
PAINT MONO (-1989 5200);
FORCEPROP 2 LAST $XR1 81 
J 0
(-1869 5200);
DISPLAY 0.638298 (-1869 5200);
PAINT MONO (-1869 5200);
FORCEPROP 2 LAST $XR0 27 
J 0
(-1779 5200);
DISPLAY 0.638298 (-1779 5200);
PAINT MONO (-1779 5200);
FORCEPROP 2 LAST CDS_LIB standard
J 0
(-1525 5200);
DISPLAY INVISIBLE (-1525 5200);
FORCEPROP 1 LAST OFFPAGE TRUE
J 2
(-1850 5075);
DISPLAY 0.872340 (-1850 5075);
PAINT GREEN (-1850 5075);
DISPLAY INVISIBLE (-1850 5075);
FORCEPROP 1 LAST COMMENT_BODY TRUE
J 2
(-1480 5105);
DISPLAY 0.872340 (-1480 5105);
PAINT PEACH (-1480 5105);
DISPLAY INVISIBLE (-1480 5105);
FORCEPROP 2 LAST PATH I253
J 0
(-1725 5250);
DISPLAY 1.021277 (-1725 5250);
DISPLAY INVISIBLE (-1725 5250);
FORCEADD OFFPAGE..2
R 2
(-1525 5150);
FORCEPROP 2 LAST $XR0 27 
J 0
(-1779 5150);
DISPLAY 0.638298 (-1779 5150);
PAINT MONO (-1779 5150);
FORCEPROP 2 LAST CDS_LIB standard
J 0
(-1525 5150);
DISPLAY INVISIBLE (-1525 5150);
FORCEPROP 1 LAST OFFPAGE TRUE
J 2
(-1850 5025);
DISPLAY 0.872340 (-1850 5025);
PAINT GREEN (-1850 5025);
DISPLAY INVISIBLE (-1850 5025);
FORCEPROP 1 LAST COMMENT_BODY TRUE
J 2
(-1480 5055);
DISPLAY 0.872340 (-1480 5055);
PAINT PEACH (-1480 5055);
DISPLAY INVISIBLE (-1480 5055);
FORCEPROP 2 LAST PATH I254
J 0
(-1725 5200);
DISPLAY 1.021277 (-1725 5200);
DISPLAY INVISIBLE (-1725 5200);
FORCEADD OFFPAGE..2
R 2
(-1525 5100);
FORCEPROP 2 LAST $XR0 27 
J 0
(-1779 5100);
DISPLAY 0.638298 (-1779 5100);
PAINT MONO (-1779 5100);
FORCEPROP 2 LAST CDS_LIB standard
J 0
(-1525 5100);
DISPLAY INVISIBLE (-1525 5100);
FORCEPROP 1 LAST OFFPAGE TRUE
J 2
(-1850 4975);
DISPLAY 0.872340 (-1850 4975);
PAINT GREEN (-1850 4975);
DISPLAY INVISIBLE (-1850 4975);
FORCEPROP 1 LAST COMMENT_BODY TRUE
J 2
(-1480 5005);
DISPLAY 0.872340 (-1480 5005);
PAINT PEACH (-1480 5005);
DISPLAY INVISIBLE (-1480 5005);
FORCEPROP 2 LAST PATH I255
J 0
(-1725 5150);
DISPLAY 1.021277 (-1725 5150);
DISPLAY INVISIBLE (-1725 5150);
FORCEADD OFFPAGE..4
(-1975 4775);
FORCEPROP 2 LAST $XR1 81 
J 0
(-1699 4775);
DISPLAY 0.638298 (-1699 4775);
PAINT MONO (-1699 4775);
FORCEPROP 2 LAST $XR0 27 
J 0
(-1789 4775);
DISPLAY 0.638298 (-1789 4775);
PAINT MONO (-1789 4775);
FORCEPROP 2 LAST CDS_LIB standard
J 2
(-1975 4775);
DISPLAY INVISIBLE (-1975 4775);
FORCEPROP 1 LAST OFFPAGE TRUE
J 0
(-1650 4650);
DISPLAY 0.872340 (-1650 4650);
PAINT GREEN (-1650 4650);
DISPLAY INVISIBLE (-1650 4650);
FORCEPROP 1 LAST COMMENT_BODY TRUE
J 0
(-2000 4675);
DISPLAY 0.872340 (-2000 4675);
PAINT GREEN (-2000 4675);
DISPLAY INVISIBLE (-2000 4675);
FORCEPROP 2 LAST PATH I257
J 0
(-1675 4825);
DISPLAY 1.021277 (-1675 4825);
DISPLAY INVISIBLE (-1675 4825);
FORCEADD OFFPAGE..3
(-2650 4225);
FORCEPROP 2 LAST $XR0 27 
J 0
(-2436 4225);
DISPLAY 0.638298 (-2436 4225);
PAINT MONO (-2436 4225);
FORCEPROP 2 LAST CDS_LIB standard
J 0
(-2650 4225);
DISPLAY INVISIBLE (-2650 4225);
FORCEPROP 1 LAST OFFPAGE TRUE
J 0
(-2325 4100);
DISPLAY 0.872340 (-2325 4100);
PAINT GREEN (-2325 4100);
DISPLAY INVISIBLE (-2325 4100);
FORCEPROP 1 LAST COMMENT_BODY TRUE
J 0
(-2700 4125);
DISPLAY 0.872340 (-2700 4125);
PAINT GREEN (-2700 4125);
DISPLAY INVISIBLE (-2700 4125);
FORCEPROP 2 LAST PATH I263
J 0
(-2425 4275);
DISPLAY 1.021277 (-2425 4275);
DISPLAY INVISIBLE (-2425 4275);
FORCEADD OFFPAGE..3
(-2650 4175);
FORCEPROP 2 LAST $XR0 27 
J 0
(-2436 4175);
DISPLAY 0.638298 (-2436 4175);
PAINT MONO (-2436 4175);
FORCEPROP 2 LAST CDS_LIB standard
J 0
(-2650 4175);
DISPLAY INVISIBLE (-2650 4175);
FORCEPROP 1 LAST OFFPAGE TRUE
J 0
(-2325 4050);
DISPLAY 0.872340 (-2325 4050);
PAINT GREEN (-2325 4050);
DISPLAY INVISIBLE (-2325 4050);
FORCEPROP 1 LAST COMMENT_BODY TRUE
J 0
(-2700 4075);
DISPLAY 0.872340 (-2700 4075);
PAINT GREEN (-2700 4075);
DISPLAY INVISIBLE (-2700 4075);
FORCEPROP 2 LAST PATH I264
J 0
(-2425 4225);
DISPLAY 1.021277 (-2425 4225);
DISPLAY INVISIBLE (-2425 4225);
FORCEADD SCONN8_G802M0083150RD3EU..1
(-500 2875);
FORCEPROP 1 LAST LOCATION J5
J 0
(-625 3290);
DISPLAY 0.489362 (-625 3290);
PAINT SKYBLUE (-625 3290);
FORCEPROP 0 LAST $SEC 1
J 0
(-625 3325);
DISPLAY 0.680851 (-625 3325);
PAINT MONO (-625 3325);
DISPLAY INVISIBLE (-625 3325);
FORCEPROP 0 LAST CDS_SEC 1
J 0
(-550 3250);
DISPLAY 1.021277 (-550 3250);
DISPLAY INVISIBLE (-550 3250);
FORCEPROP 0 LASTPIN (-775 2950) $PN 1
J 2
(-785 2960);
DISPLAY 0.489362 (-785 2960);
PAINT MONO (-785 2960);
FORCEPROP 0 LASTPIN (-225 2950) $PN 2
J 0
(-215 2960);
DISPLAY 0.489362 (-215 2960);
PAINT MONO (-215 2960);
FORCEPROP 0 LASTPIN (-775 2900) $PN 3
J 2
(-785 2910);
DISPLAY 0.489362 (-785 2910);
PAINT MONO (-785 2910);
FORCEPROP 0 LASTPIN (-225 2900) $PN 4
J 0
(-215 2910);
DISPLAY 0.489362 (-215 2910);
PAINT MONO (-215 2910);
FORCEPROP 0 LASTPIN (-775 2850) $PN 5
J 2
(-785 2860);
DISPLAY 0.489362 (-785 2860);
PAINT MONO (-785 2860);
FORCEPROP 0 LASTPIN (-225 2850) $PN 6
J 0
(-215 2860);
DISPLAY 0.489362 (-215 2860);
PAINT MONO (-215 2860);
FORCEPROP 0 LASTPIN (-775 2800) $PN 7
J 2
(-785 2810);
DISPLAY 0.489362 (-785 2810);
PAINT MONO (-785 2810);
FORCEPROP 0 LASTPIN (-225 2800) $PN 8
J 0
(-215 2810);
DISPLAY 0.489362 (-215 2810);
PAINT MONO (-215 2810);
FORCEPROP 2 LAST PART_TYPE SMLF
J 0
(-625 3200);
DISPLAY 1.021277 (-625 3200);
FORCEPROP 1 LAST MATERIAL IO
J 0
(-625 3016);
DISPLAY 0.489362 (-625 3016);
PAINT SKYBLUE (-625 3016);
FORCEPROP 2 LAST VALUE SCONN8_G802M0083150RD3EU
J 0
(-625 3150);
DISPLAY 0.489362 (-625 3150);
PAINT SKYBLUE (-625 3150);
FORCEPROP 1 LAST PART_NUMBER DFHD08MS351
J 0
(-625 3075);
DISPLAY 0.489362 (-625 3075);
PAINT SKYBLUE (-625 3075);
FORCEPROP 1 LAST CDS_LMAN_SYM_OUTLINE -125,125,125,-125
J 0
(-500 2875);
DISPLAY 0.468085 (-500 2875);
PAINT GREEN (-500 2875);
DISPLAY INVISIBLE (-500 2875);
FORCEPROP 1 LAST NEEDS_NO_SIZE TRUE
J 0
(-500 2875);
DISPLAY 0.723404 (-500 2875);
PAINT GREEN (-500 2875);
DISPLAY INVISIBLE (-500 2875);
FORCEPROP 2 LAST CDS_LIB pure_quanta
J 0
(-500 2875);
DISPLAY INVISIBLE (-500 2875);
FORCEPROP 1 LAST PATH I266
J 0
(-500 2875);
DISPLAY 0.723404 (-500 2875);
PAINT GREEN (-500 2875);
DISPLAY INVISIBLE (-500 2875);
FORCEADD OFFPAGE..2
(-1400 1475);
FORCEPROP 2 LAST $XR0 141 
J 0
(-1211 1475);
DISPLAY 0.638298 (-1211 1475);
PAINT MONO (-1211 1475);
FORCEPROP 2 LAST CDS_LIB standard
J 0
(-1400 1475);
DISPLAY INVISIBLE (-1400 1475);
FORCEPROP 1 LAST OFFPAGE TRUE
J 0
(-1075 1350);
DISPLAY 0.872340 (-1075 1350);
PAINT GREEN (-1075 1350);
DISPLAY INVISIBLE (-1075 1350);
FORCEPROP 1 LAST COMMENT_BODY TRUE
J 0
(-1445 1380);
DISPLAY 0.872340 (-1445 1380);
PAINT GREEN (-1445 1380);
DISPLAY INVISIBLE (-1445 1380);
FORCEPROP 2 LAST PATH I273
J 0
(-1200 1525);
DISPLAY 1.021277 (-1200 1525);
DISPLAY INVISIBLE (-1200 1525);
FORCEADD OFFPAGE..4
(-1400 1425);
FORCEPROP 2 LAST $XR0 141 
J 0
(-1214 1425);
DISPLAY 0.638298 (-1214 1425);
PAINT MONO (-1214 1425);
FORCEPROP 2 LAST CDS_LIB standard
J 2
(-1400 1425);
DISPLAY INVISIBLE (-1400 1425);
FORCEPROP 1 LAST OFFPAGE TRUE
J 0
(-1075 1300);
DISPLAY 0.872340 (-1075 1300);
PAINT GREEN (-1075 1300);
DISPLAY INVISIBLE (-1075 1300);
FORCEPROP 1 LAST COMMENT_BODY TRUE
J 0
(-1425 1325);
DISPLAY 0.872340 (-1425 1325);
PAINT GREEN (-1425 1325);
DISPLAY INVISIBLE (-1425 1325);
FORCEPROP 2 LAST PATH I274
J 0
(-1200 1475);
DISPLAY 1.021277 (-1200 1475);
DISPLAY INVISIBLE (-1200 1475);
FORCEADD OFFPAGE..4
(-1400 1325);
FORCEPROP 2 LAST $XR0 141 
J 0
(-1214 1325);
DISPLAY 0.638298 (-1214 1325);
PAINT MONO (-1214 1325);
FORCEPROP 2 LAST CDS_LIB standard
J 2
(-1400 1325);
DISPLAY INVISIBLE (-1400 1325);
FORCEPROP 1 LAST OFFPAGE TRUE
J 0
(-1075 1200);
DISPLAY 0.872340 (-1075 1200);
PAINT GREEN (-1075 1200);
DISPLAY INVISIBLE (-1075 1200);
FORCEPROP 1 LAST COMMENT_BODY TRUE
J 0
(-1425 1225);
DISPLAY 0.872340 (-1425 1225);
PAINT GREEN (-1425 1225);
DISPLAY INVISIBLE (-1425 1225);
FORCEPROP 2 LAST PATH I275
J 0
(-1200 1375);
DISPLAY 1.021277 (-1200 1375);
DISPLAY INVISIBLE (-1200 1375);
FORCEADD OFFPAGE..2
(-1400 1375);
FORCEPROP 2 LAST $XR1 141 
J 0
(-1121 1375);
DISPLAY 0.638298 (-1121 1375);
PAINT MONO (-1121 1375);
FORCEPROP 2 LAST $XR0 75 
J 0
(-1211 1375);
DISPLAY 0.638298 (-1211 1375);
PAINT MONO (-1211 1375);
FORCEPROP 2 LAST CDS_LIB standard
J 0
(-1400 1375);
DISPLAY INVISIBLE (-1400 1375);
FORCEPROP 1 LAST OFFPAGE TRUE
J 0
(-1075 1250);
DISPLAY 0.872340 (-1075 1250);
PAINT GREEN (-1075 1250);
DISPLAY INVISIBLE (-1075 1250);
FORCEPROP 1 LAST COMMENT_BODY TRUE
J 0
(-1445 1280);
DISPLAY 0.872340 (-1445 1280);
PAINT GREEN (-1445 1280);
DISPLAY INVISIBLE (-1445 1280);
FORCEPROP 2 LAST PATH I276
J 0
(-1075 1425);
DISPLAY 1.021277 (-1075 1425);
DISPLAY INVISIBLE (-1075 1425);
FORCEADD OFFPAGE..3
(-2650 4125);
FORCEPROP 2 LAST $XR0 27 
J 0
(-2436 4125);
DISPLAY 0.638298 (-2436 4125);
PAINT MONO (-2436 4125);
FORCEPROP 2 LAST CDS_LIB standard
J 0
(-2650 4125);
DISPLAY INVISIBLE (-2650 4125);
FORCEPROP 1 LAST OFFPAGE TRUE
J 0
(-2325 4000);
DISPLAY 0.872340 (-2325 4000);
PAINT GREEN (-2325 4000);
DISPLAY INVISIBLE (-2325 4000);
FORCEPROP 1 LAST COMMENT_BODY TRUE
J 0
(-2700 4025);
DISPLAY 0.872340 (-2700 4025);
PAINT GREEN (-2700 4025);
DISPLAY INVISIBLE (-2700 4025);
FORCEPROP 2 LAST PATH I277
J 0
(-2425 4175);
DISPLAY 1.021277 (-2425 4175);
DISPLAY INVISIBLE (-2425 4175);
FORCEADD OFFPAGE..3
(-2650 4075);
FORCEPROP 2 LAST $XR0 27 
J 0
(-2436 4075);
DISPLAY 0.638298 (-2436 4075);
PAINT MONO (-2436 4075);
FORCEPROP 2 LAST CDS_LIB standard
J 0
(-2650 4075);
DISPLAY INVISIBLE (-2650 4075);
FORCEPROP 1 LAST OFFPAGE TRUE
J 0
(-2325 3950);
DISPLAY 0.872340 (-2325 3950);
PAINT GREEN (-2325 3950);
DISPLAY INVISIBLE (-2325 3950);
FORCEPROP 1 LAST COMMENT_BODY TRUE
J 0
(-2700 3975);
DISPLAY 0.872340 (-2700 3975);
PAINT GREEN (-2700 3975);
DISPLAY INVISIBLE (-2700 3975);
FORCEPROP 2 LAST PATH I278
J 0
(-2425 4125);
DISPLAY 1.021277 (-2425 4125);
DISPLAY INVISIBLE (-2425 4125);
FORCEADD Q_RES..1
R 2
(-2375 1475);
FORCEPROP 1 LAST LOCATION R405
J 2
(-2525 1475);
DISPLAY 0.489362 (-2525 1475);
PAINT SKYBLUE (-2525 1475);
FORCEPROP 0 LAST $SEC 1
J 0
(-2525 1525);
DISPLAY 0.680851 (-2525 1525);
PAINT MONO (-2525 1525);
DISPLAY INVISIBLE (-2525 1525);
FORCEPROP 0 LAST CDS_SEC 1
J 0
(-2525 1525);
DISPLAY 1.021277 (-2525 1525);
DISPLAY INVISIBLE (-2525 1525);
FORCEPROP 1 LASTPIN (-2275 1475) $PN 1
J 2
(-2287 1487);
DISPLAY 0.489362 (-2287 1487);
PAINT MONO (-2287 1487);
FORCEPROP 1 LASTPIN (-2475 1475) $PN 2
J 2
(-2437 1487);
DISPLAY 0.489362 (-2437 1487);
PAINT MONO (-2437 1487);
FORCEPROP 1 LAST VALUE 0
J 0
(-2275 1475);
DISPLAY 0.489362 (-2275 1475);
PAINT SKYBLUE (-2275 1475);
FORCEPROP 2 LAST CDS_LIB pure_quanta
J 0
(-2375 1475);
DISPLAY INVISIBLE (-2375 1475);
FORCEPROP 1 LAST PATH I279
J 2
(-2325 1625);
DISPLAY 0.978723 (-2325 1625);
PAINT WHITE (-2325 1625);
DISPLAY INVISIBLE (-2325 1625);
FORCEPROP 1 LAST WATTAGE 1/16W
J 0
(-2775 1400);
DISPLAY 0.489362 (-2775 1400);
PAINT SKYBLUE (-2775 1400);
DISPLAY INVISIBLE (-2775 1400);
FORCEPROP 1 LAST MATERIAL CHIP
J 2
(-2800 1400);
DISPLAY 0.489362 (-2800 1400);
PAINT SKYBLUE (-2800 1400);
DISPLAY INVISIBLE (-2800 1400);
FORCEPROP 1 LAST TOLERANCE 5%
J 2
(-2350 1400);
DISPLAY 0.489362 (-2350 1400);
PAINT SKYBLUE (-2350 1400);
DISPLAY INVISIBLE (-2350 1400);
FORCEPROP 1 LAST PART_NUMBER CS00002JB38
J 2
(-2400 1525);
DISPLAY 0.489362 (-2400 1525);
PAINT SKYBLUE (-2400 1525);
DISPLAY INVISIBLE (-2400 1525);
FORCEPROP 1 LAST PACK_TYPE 0402LF
J 2
(-2425 1400);
DISPLAY 0.489362 (-2425 1400);
PAINT SKYBLUE (-2425 1400);
DISPLAY INVISIBLE (-2425 1400);
FORCEADD SCONN8_G802M0083150RD3EU..1
(-500 2250);
FORCEPROP 1 LAST LOCATION J48
J 0
(-625 2665);
DISPLAY 0.489362 (-625 2665);
PAINT SKYBLUE (-625 2665);
FORCEPROP 0 LAST $SEC 1
J 0
(-625 2700);
DISPLAY 0.680851 (-625 2700);
PAINT MONO (-625 2700);
DISPLAY INVISIBLE (-625 2700);
FORCEPROP 0 LAST CDS_SEC 1
J 0
(-550 2625);
DISPLAY 1.021277 (-550 2625);
DISPLAY INVISIBLE (-550 2625);
FORCEPROP 0 LASTPIN (-775 2325) $PN 1
J 2
(-785 2335);
DISPLAY 0.489362 (-785 2335);
PAINT MONO (-785 2335);
FORCEPROP 0 LASTPIN (-225 2325) $PN 2
J 0
(-215 2335);
DISPLAY 0.489362 (-215 2335);
PAINT MONO (-215 2335);
FORCEPROP 0 LASTPIN (-775 2275) $PN 3
J 2
(-785 2285);
DISPLAY 0.489362 (-785 2285);
PAINT MONO (-785 2285);
FORCEPROP 0 LASTPIN (-225 2275) $PN 4
J 0
(-215 2285);
DISPLAY 0.489362 (-215 2285);
PAINT MONO (-215 2285);
FORCEPROP 0 LASTPIN (-775 2225) $PN 5
J 2
(-785 2235);
DISPLAY 0.489362 (-785 2235);
PAINT MONO (-785 2235);
FORCEPROP 0 LASTPIN (-225 2225) $PN 6
J 0
(-215 2235);
DISPLAY 0.489362 (-215 2235);
PAINT MONO (-215 2235);
FORCEPROP 0 LASTPIN (-775 2175) $PN 7
J 2
(-785 2185);
DISPLAY 0.489362 (-785 2185);
PAINT MONO (-785 2185);
FORCEPROP 0 LASTPIN (-225 2175) $PN 8
J 0
(-215 2185);
DISPLAY 0.489362 (-215 2185);
PAINT MONO (-215 2185);
FORCEPROP 2 LAST PART_TYPE SMLF
J 0
(-625 2575);
DISPLAY 1.021277 (-625 2575);
FORCEPROP 1 LAST MATERIAL IO
J 0
(-625 2391);
DISPLAY 0.489362 (-625 2391);
PAINT SKYBLUE (-625 2391);
FORCEPROP 2 LAST VALUE SCONN8_G802M0083150RD3EU
J 0
(-625 2525);
DISPLAY 0.489362 (-625 2525);
PAINT SKYBLUE (-625 2525);
FORCEPROP 1 LAST PART_NUMBER DFHD08MS351
J 0
(-625 2450);
DISPLAY 0.489362 (-625 2450);
PAINT SKYBLUE (-625 2450);
FORCEPROP 2 LAST CDS_LIB pure_quanta
J 0
(-500 2250);
DISPLAY INVISIBLE (-500 2250);
FORCEPROP 1 LAST NEEDS_NO_SIZE TRUE
J 0
(-500 2250);
DISPLAY 0.723404 (-500 2250);
PAINT GREEN (-500 2250);
DISPLAY INVISIBLE (-500 2250);
FORCEPROP 1 LAST CDS_LMAN_SYM_OUTLINE -125,125,125,-125
J 0
(-500 2250);
DISPLAY 0.468085 (-500 2250);
PAINT GREEN (-500 2250);
DISPLAY INVISIBLE (-500 2250);
FORCEPROP 1 LAST PATH I282
J 0
(-500 2250);
DISPLAY 0.723404 (-500 2250);
PAINT GREEN (-500 2250);
DISPLAY INVISIBLE (-500 2250);
FORCEADD OFFPAGE..2
R 2
(-1250 2175);
FORCEPROP 2 LAST $XR0 27 
J 0
(-1474 2175);
DISPLAY 0.638298 (-1474 2175);
PAINT MONO (-1474 2175);
FORCEPROP 2 LAST CDS_LIB standard
J 0
(-1250 2175);
DISPLAY INVISIBLE (-1250 2175);
FORCEPROP 1 LAST OFFPAGE TRUE
J 2
(-1575 2050);
DISPLAY 0.872340 (-1575 2050);
PAINT GREEN (-1575 2050);
DISPLAY INVISIBLE (-1575 2050);
FORCEPROP 1 LAST COMMENT_BODY TRUE
J 2
(-1205 2080);
DISPLAY 0.872340 (-1205 2080);
PAINT PEACH (-1205 2080);
DISPLAY INVISIBLE (-1205 2080);
FORCEPROP 2 LAST PATH I283
J 0
(-1200 2250);
DISPLAY 1.021277 (-1200 2250);
DISPLAY INVISIBLE (-1200 2250);
FORCEADD OFFPAGE..2
R 2
(-1250 2225);
FORCEPROP 2 LAST $XR0 27 
J 0
(-1474 2225);
DISPLAY 0.638298 (-1474 2225);
PAINT MONO (-1474 2225);
FORCEPROP 2 LAST CDS_LIB standard
J 0
(-1250 2225);
DISPLAY INVISIBLE (-1250 2225);
FORCEPROP 1 LAST OFFPAGE TRUE
J 2
(-1575 2100);
DISPLAY 0.872340 (-1575 2100);
PAINT GREEN (-1575 2100);
DISPLAY INVISIBLE (-1575 2100);
FORCEPROP 1 LAST COMMENT_BODY TRUE
J 2
(-1205 2130);
DISPLAY 0.872340 (-1205 2130);
PAINT PEACH (-1205 2130);
DISPLAY INVISIBLE (-1205 2130);
FORCEPROP 2 LAST PATH I284
J 0
(-1200 2300);
DISPLAY 1.021277 (-1200 2300);
DISPLAY INVISIBLE (-1200 2300);
FORCEADD OFFPAGE..2
R 2
(-1250 2275);
FORCEPROP 2 LAST $XR0 27 
J 0
(-1474 2275);
DISPLAY 0.638298 (-1474 2275);
PAINT MONO (-1474 2275);
FORCEPROP 2 LAST CDS_LIB standard
J 0
(-1250 2275);
DISPLAY INVISIBLE (-1250 2275);
FORCEPROP 1 LAST OFFPAGE TRUE
J 2
(-1575 2150);
DISPLAY 0.872340 (-1575 2150);
PAINT GREEN (-1575 2150);
DISPLAY INVISIBLE (-1575 2150);
FORCEPROP 1 LAST COMMENT_BODY TRUE
J 2
(-1205 2180);
DISPLAY 0.872340 (-1205 2180);
PAINT PEACH (-1205 2180);
DISPLAY INVISIBLE (-1205 2180);
FORCEPROP 2 LAST PATH I285
J 0
(-1200 2350);
DISPLAY 1.021277 (-1200 2350);
DISPLAY INVISIBLE (-1200 2350);
FORCEADD OFFPAGE..2
R 2
(-1250 2325);
FORCEPROP 2 LAST $XR0 27 
J 0
(-1474 2325);
DISPLAY 0.638298 (-1474 2325);
PAINT MONO (-1474 2325);
FORCEPROP 2 LAST CDS_LIB standard
J 0
(-1250 2325);
DISPLAY INVISIBLE (-1250 2325);
FORCEPROP 1 LAST OFFPAGE TRUE
J 2
(-1575 2200);
DISPLAY 0.872340 (-1575 2200);
PAINT GREEN (-1575 2200);
DISPLAY INVISIBLE (-1575 2200);
FORCEPROP 1 LAST COMMENT_BODY TRUE
J 2
(-1205 2230);
DISPLAY 0.872340 (-1205 2230);
PAINT PEACH (-1205 2230);
DISPLAY INVISIBLE (-1205 2230);
FORCEPROP 2 LAST PATH I286
J 0
(-1200 2400);
DISPLAY 1.021277 (-1200 2400);
DISPLAY INVISIBLE (-1200 2400);
FORCEADD Q_RES..1
(-2375 1375);
FORCEPROP 1 LAST LOCATION R2318
J 0
(-2575 1375);
DISPLAY 0.489362 (-2575 1375);
PAINT SKYBLUE (-2575 1375);
FORCEPROP 0 LAST $SEC 1
J 0
(-2225 1400);
DISPLAY 0.680851 (-2225 1400);
PAINT MONO (-2225 1400);
DISPLAY INVISIBLE (-2225 1400);
FORCEPROP 0 LAST CDS_SEC 1
J 0
(-2225 1400);
DISPLAY 1.021277 (-2225 1400);
DISPLAY INVISIBLE (-2225 1400);
FORCEPROP 1 LASTPIN (-2475 1375) $PN 1
J 0
(-2463 1387);
DISPLAY 0.489362 (-2463 1387);
PAINT MONO (-2463 1387);
FORCEPROP 1 LASTPIN (-2275 1375) $PN 2
J 0
(-2313 1387);
DISPLAY 0.489362 (-2313 1387);
PAINT MONO (-2313 1387);
FORCEPROP 1 LAST VALUE 0
J 2
(-2225 1375);
DISPLAY 0.489362 (-2225 1375);
PAINT SKYBLUE (-2225 1375);
FORCEPROP 2 LAST CDS_LIB pure_quanta
J 0
(-2375 1375);
DISPLAY INVISIBLE (-2375 1375);
FORCEPROP 1 LAST PATH I288
J 0
(-2425 1525);
DISPLAY 0.978723 (-2425 1525);
PAINT WHITE (-2425 1525);
DISPLAY INVISIBLE (-2425 1525);
FORCEPROP 1 LAST WATTAGE 1/16W
J 2
(-1975 1300);
DISPLAY 0.489362 (-1975 1300);
PAINT SKYBLUE (-1975 1300);
DISPLAY INVISIBLE (-1975 1300);
FORCEPROP 1 LAST MATERIAL CHIP
J 0
(-1950 1300);
DISPLAY 0.489362 (-1950 1300);
PAINT SKYBLUE (-1950 1300);
DISPLAY INVISIBLE (-1950 1300);
FORCEPROP 1 LAST TOLERANCE 5%
J 0
(-2400 1300);
DISPLAY 0.489362 (-2400 1300);
PAINT SKYBLUE (-2400 1300);
DISPLAY INVISIBLE (-2400 1300);
FORCEPROP 1 LAST PART_NUMBER CS00002JB38
J 0
(-2350 1425);
DISPLAY 0.489362 (-2350 1425);
PAINT SKYBLUE (-2350 1425);
DISPLAY INVISIBLE (-2350 1425);
FORCEPROP 1 LAST PACK_TYPE 0402LF
J 0
(-2325 1300);
DISPLAY 0.489362 (-2325 1300);
PAINT SKYBLUE (-2325 1300);
DISPLAY INVISIBLE (-2325 1300);
FORCEADD UNIVERSAL_POWER..1
(-8000 1575);
FORCEPROP 3 LASTPIN (-8000 1525) SIG_NAME PVDD18_S5_P0\g
J 0
(-7990 1535);
DISPLAY 0.659574 (-7990 1535);
PAINT MONO (-7990 1535);
DISPLAY INVISIBLE (-7990 1535);
FORCEPROP 1 LAST HDL_POWER PVDD18_S5_P0
J 1
(-8000 1625);
DISPLAY 0.489362 (-8000 1625);
PAINT GREEN (-8000 1625);
FORCEPROP 2 LAST CDS_LIB pure_quanta_power
J 0
(-8000 1575);
DISPLAY INVISIBLE (-8000 1575);
FORCEPROP 1 LAST PATH I293
J 0
(-7950 1600);
DISPLAY 0.872340 (-7950 1600);
PAINT AQUA (-7950 1600);
DISPLAY INVISIBLE (-7950 1600);
FORCEADD Q_RES..2
(-6375 1300);
FORCEPROP 1 LAST LOCATION R403
J 0
(-6350 1400);
DISPLAY 0.489362 (-6350 1400);
PAINT SKYBLUE (-6350 1400);
FORCEPROP 0 LAST $SEC 1
J 0
(-6350 1450);
DISPLAY 0.680851 (-6350 1450);
PAINT MONO (-6350 1450);
DISPLAY INVISIBLE (-6350 1450);
FORCEPROP 0 LAST CDS_SEC 1
J 0
(-6350 1450);
DISPLAY 1.021277 (-6350 1450);
DISPLAY INVISIBLE (-6350 1450);
FORCEPROP 1 LASTPIN (-6375 1400) $PN 1
J 0
(-6370 1362);
DISPLAY 0.489362 (-6370 1362);
PAINT MONO (-6370 1362);
FORCEPROP 1 LASTPIN (-6375 1200) $PN 2
J 0
(-6370 1210);
DISPLAY 0.489362 (-6370 1210);
PAINT MONO (-6370 1210);
FORCEPROP 1 LAST WATTAGE 1/16W
J 0
(-6350 1250);
DISPLAY 0.489362 (-6350 1250);
PAINT SKYBLUE (-6350 1250);
FORCEPROP 1 LAST MATERIAL CHIP
J 0
(-6350 1200);
DISPLAY 0.489362 (-6350 1200);
PAINT SKYBLUE (-6350 1200);
FORCEPROP 1 LAST TOLERANCE 5%
J 0
(-6350 1300);
DISPLAY 0.489362 (-6350 1300);
PAINT SKYBLUE (-6350 1300);
FORCEPROP 1 LAST VALUE 1K
J 0
(-6350 1350);
DISPLAY 0.489362 (-6350 1350);
PAINT SKYBLUE (-6350 1350);
FORCEPROP 1 LAST PACK_TYPE 0402LF
J 0
(-6350 1150);
DISPLAY 0.489362 (-6350 1150);
PAINT SKYBLUE (-6350 1150);
FORCEPROP 2 LAST CDS_LIB pure_quanta
J 0
(-6375 1300);
DISPLAY INVISIBLE (-6375 1300);
FORCEPROP 1 LAST PATH I294
J 0
(-6325 1475);
DISPLAY 0.978723 (-6325 1475);
PAINT WHITE (-6325 1475);
DISPLAY INVISIBLE (-6325 1475);
FORCEPROP 1 LAST PART_NUMBER TMP_QCS21002JB34
J 0
(-6350 1100);
DISPLAY 0.489362 (-6350 1100);
PAINT SKYBLUE (-6350 1100);
DISPLAY INVISIBLE (-6350 1100);
FORCEADD Q_CAP..1
(-6375 600);
FORCEPROP 1 LAST LOCATION C212
J 0
(-6325 700);
DISPLAY 0.489362 (-6325 700);
PAINT SKYBLUE (-6325 700);
FORCEPROP 0 LAST $SEC 1
J 0
(-6325 750);
DISPLAY 0.680851 (-6325 750);
PAINT MONO (-6325 750);
DISPLAY INVISIBLE (-6325 750);
FORCEPROP 0 LAST CDS_SEC 1
J 0
(-6325 750);
DISPLAY 1.021277 (-6325 750);
DISPLAY INVISIBLE (-6325 750);
FORCEPROP 1 LASTPIN (-6375 700) $PN 1
J 0
(-6365 680);
DISPLAY 0.489362 (-6365 680);
PAINT MONO (-6365 680);
FORCEPROP 1 LASTPIN (-6375 500) $PN 2
J 0
(-6365 480);
DISPLAY 0.489362 (-6365 480);
PAINT MONO (-6365 480);
FORCEPROP 1 LAST MATERIAL EMPTY
J 0
(-6325 400);
DISPLAY 0.489362 (-6325 400);
PAINT RED (-6325 400);
FORCEPROP 1 LAST TOLERANCE 10%
J 0
(-6325 550);
DISPLAY 0.489362 (-6325 550);
PAINT SKYBLUE (-6325 550);
FORCEPROP 1 LAST VALUE 0.001UF
J 0
(-6325 650);
DISPLAY 0.489362 (-6325 650);
PAINT SKYBLUE (-6325 650);
FORCEPROP 1 LAST PART_NUMBER CH30106KB19
J 0
(-6325 500);
DISPLAY 0.489362 (-6325 500);
PAINT SKYBLUE (-6325 500);
FORCEPROP 1 LAST VOLTAGE 50V
J 0
(-6325 600);
DISPLAY 0.489362 (-6325 600);
PAINT SKYBLUE (-6325 600);
FORCEPROP 1 LAST PACK_TYPE C0402
J 0
(-6325 450);
DISPLAY 0.489362 (-6325 450);
PAINT SKYBLUE (-6325 450);
FORCEPROP 2 LAST CDS_LIB pure_quanta
J 0
(-6375 600);
DISPLAY INVISIBLE (-6375 600);
FORCEPROP 1 LAST PATH I295
J 0
(-6325 750);
DISPLAY 0.978723 (-6325 750);
PAINT WHITE (-6325 750);
DISPLAY INVISIBLE (-6325 750);
FORCEADD Q_RES..2
(-6675 1300);
FORCEPROP 1 LAST LOCATION R402
J 0
(-6650 1400);
DISPLAY 0.489362 (-6650 1400);
PAINT SKYBLUE (-6650 1400);
FORCEPROP 2 LAST $SEC 1
J 0
(-6625 1525);
DISPLAY 0.680851 (-6625 1525);
PAINT MONO (-6625 1525);
DISPLAY INVISIBLE (-6625 1525);
FORCEPROP 2 LAST CDS_SEC 1
J 0
(-6625 1525);
DISPLAY 1.021277 (-6625 1525);
DISPLAY INVISIBLE (-6625 1525);
FORCEPROP 1 LASTPIN (-6675 1400) $PN 1
J 0
(-6670 1362);
DISPLAY 0.489362 (-6670 1362);
FORCEPROP 1 LASTPIN (-6675 1200) $PN 2
J 0
(-6670 1210);
DISPLAY 0.489362 (-6670 1210);
FORCEPROP 1 LAST WATTAGE 1/16W
J 0
(-6650 1250);
DISPLAY 0.489362 (-6650 1250);
PAINT SKYBLUE (-6650 1250);
FORCEPROP 1 LAST MATERIAL CHIP
J 0
(-6650 1200);
DISPLAY 0.489362 (-6650 1200);
PAINT SKYBLUE (-6650 1200);
FORCEPROP 1 LAST TOLERANCE 5%
J 0
(-6650 1300);
DISPLAY 0.489362 (-6650 1300);
PAINT SKYBLUE (-6650 1300);
FORCEPROP 1 LAST VALUE 1K
J 0
(-6650 1350);
DISPLAY 0.489362 (-6650 1350);
PAINT SKYBLUE (-6650 1350);
FORCEPROP 1 LAST PACK_TYPE 0402LF
J 0
(-6650 1150);
DISPLAY 0.489362 (-6650 1150);
PAINT SKYBLUE (-6650 1150);
FORCEPROP 2 LAST CDS_LIB pure_quanta
J 0
(-6675 1300);
DISPLAY INVISIBLE (-6675 1300);
FORCEPROP 1 LAST PATH I296
J 0
(-6625 1475);
DISPLAY 0.978723 (-6625 1475);
PAINT WHITE (-6625 1475);
DISPLAY INVISIBLE (-6625 1475);
FORCEPROP 1 LAST PART_NUMBER TMP_QCS21002JB34
J 0
(-6635 1175);
DISPLAY 0.617021 (-6635 1175);
PAINT SKYBLUE (-6635 1175);
DISPLAY INVISIBLE (-6635 1175);
FORCEADD Q_CAP..1
(-6675 600);
FORCEPROP 1 LAST LOCATION C211
J 0
(-6625 700);
DISPLAY 0.489362 (-6625 700);
PAINT SKYBLUE (-6625 700);
FORCEPROP 0 LAST $SEC 1
J 0
(-6625 750);
PAINT MONO (-6625 750);
DISPLAY INVISIBLE (-6625 750);
FORCEPROP 0 LAST CDS_SEC 1
J 0
(-6625 750);
PAINT MONO (-6625 750);
DISPLAY INVISIBLE (-6625 750);
FORCEPROP 1 LASTPIN (-6675 700) $PN 1
J 0
(-6665 680);
DISPLAY 0.489362 (-6665 680);
PAINT GREEN (-6665 680);
FORCEPROP 1 LASTPIN (-6675 500) $PN 2
J 0
(-6665 480);
DISPLAY 0.489362 (-6665 480);
PAINT GREEN (-6665 480);
FORCEPROP 1 LAST MATERIAL EMPTY
J 0
(-6625 400);
DISPLAY 0.489362 (-6625 400);
PAINT RED (-6625 400);
FORCEPROP 1 LAST TOLERANCE 10%
J 0
(-6625 550);
DISPLAY 0.489362 (-6625 550);
PAINT SKYBLUE (-6625 550);
FORCEPROP 1 LAST VALUE 0.001UF
J 0
(-6625 650);
DISPLAY 0.489362 (-6625 650);
PAINT SKYBLUE (-6625 650);
FORCEPROP 1 LAST VOLTAGE 50V
J 0
(-6625 600);
DISPLAY 0.489362 (-6625 600);
PAINT SKYBLUE (-6625 600);
FORCEPROP 1 LAST PACK_TYPE C0402
J 0
(-6625 450);
DISPLAY 0.489362 (-6625 450);
PAINT SKYBLUE (-6625 450);
FORCEPROP 2 LAST CDS_LIB pure_quanta
J 0
(-6675 600);
PAINT MONO (-6675 600);
DISPLAY INVISIBLE (-6675 600);
FORCEPROP 1 LAST PATH I297
J 0
(-6625 750);
DISPLAY 0.978723 (-6625 750);
PAINT WHITE (-6625 750);
DISPLAY INVISIBLE (-6625 750);
FORCEPROP 1 LAST PART_NUMBER CH30106KB19
J 0
(-6625 500);
DISPLAY 0.808511 (-6625 500);
PAINT SKYBLUE (-6625 500);
DISPLAY INVISIBLE (-6625 500);
FORCEADD GND..1
(-6375 300);
FORCEPROP 3 LASTPIN (-6375 350) SIG_NAME GND\g
J 0
(-6365 360);
DISPLAY 0.659574 (-6365 360);
PAINT MONO (-6365 360);
DISPLAY INVISIBLE (-6365 360);
FORCEPROP 1 LAST SIZE 1B
J 0
(-6300 250);
DISPLAY 0.872340 (-6300 250);
PAINT GREEN (-6300 250);
DISPLAY INVISIBLE (-6300 250);
FORCEPROP 2 LAST CDS_LIB pure_quanta_power
J 0
(-6375 300);
DISPLAY INVISIBLE (-6375 300);
FORCEPROP 1 LAST PATH I298
J 0
(-6300 300);
DISPLAY 0.872340 (-6300 300);
PAINT AQUA (-6300 300);
DISPLAY INVISIBLE (-6300 300);
FORCEPROP 1 LAST HDL_POWER GND
J 0
(-6375 450);
DISPLAY 0.872340 (-6375 450);
PAINT GREEN (-6375 450);
DISPLAY INVISIBLE (-6375 450);
FORCEADD GND..1
(-6675 300);
FORCEPROP 3 LASTPIN (-6675 350) SIG_NAME GND\g
J 0
(-6665 360);
DISPLAY 0.659574 (-6665 360);
PAINT MONO (-6665 360);
DISPLAY INVISIBLE (-6665 360);
FORCEPROP 1 LAST SIZE 1B
J 0
(-6600 250);
DISPLAY 0.872340 (-6600 250);
PAINT GREEN (-6600 250);
DISPLAY INVISIBLE (-6600 250);
FORCEPROP 2 LAST CDS_LIB pure_quanta_power
J 0
(-6675 300);
DISPLAY INVISIBLE (-6675 300);
FORCEPROP 1 LAST PATH I299
J 0
(-6600 300);
DISPLAY 0.872340 (-6600 300);
PAINT AQUA (-6600 300);
DISPLAY INVISIBLE (-6600 300);
FORCEPROP 1 LAST HDL_POWER GND
J 0
(-6675 450);
DISPLAY 0.872340 (-6675 450);
PAINT GREEN (-6675 450);
DISPLAY INVISIBLE (-6675 450);
FORCEADD UNIVERSAL_GND..1
(-5250 975);
FORCEPROP 3 LASTPIN (-5250 1025) SIG_NAME GND\g
J 0
(-5240 1035);
DISPLAY 0.659574 (-5240 1035);
PAINT MONO (-5240 1035);
DISPLAY INVISIBLE (-5240 1035);
FORCEPROP 2 LAST CDS_LIB pure_quanta_power
J 0
(-5250 975);
DISPLAY INVISIBLE (-5250 975);
FORCEPROP 1 LAST PATH I3
J 0
(-5175 975);
DISPLAY 0.872340 (-5175 975);
PAINT AQUA (-5175 975);
DISPLAY INVISIBLE (-5175 975);
FORCEPROP 1 LAST HDL_POWER GND
J 1
(-5225 900);
DISPLAY 0.872340 (-5225 900);
PAINT GREEN (-5225 900);
DISPLAY INVISIBLE (-5225 900);
FORCEADD Q_RES..2
(-7025 1300);
FORCEPROP 1 LAST LOCATION R401
J 0
(-7000 1400);
DISPLAY 0.489362 (-7000 1400);
PAINT SKYBLUE (-7000 1400);
FORCEPROP 2 LAST $SEC 1
J 0
(-6975 1525);
DISPLAY 0.680851 (-6975 1525);
PAINT MONO (-6975 1525);
DISPLAY INVISIBLE (-6975 1525);
FORCEPROP 2 LAST CDS_SEC 1
J 0
(-6975 1525);
DISPLAY 1.021277 (-6975 1525);
DISPLAY INVISIBLE (-6975 1525);
FORCEPROP 1 LASTPIN (-7025 1400) $PN 1
J 0
(-7020 1362);
DISPLAY 0.489362 (-7020 1362);
FORCEPROP 1 LASTPIN (-7025 1200) $PN 2
J 0
(-7020 1210);
DISPLAY 0.489362 (-7020 1210);
FORCEPROP 1 LAST WATTAGE 1/16W
J 0
(-7000 1250);
DISPLAY 0.489362 (-7000 1250);
PAINT SKYBLUE (-7000 1250);
FORCEPROP 1 LAST MATERIAL CHIP
J 0
(-7000 1200);
DISPLAY 0.489362 (-7000 1200);
PAINT SKYBLUE (-7000 1200);
FORCEPROP 1 LAST TOLERANCE 5%
J 0
(-7000 1300);
DISPLAY 0.489362 (-7000 1300);
PAINT SKYBLUE (-7000 1300);
FORCEPROP 1 LAST VALUE 1K
J 0
(-7000 1350);
DISPLAY 0.489362 (-7000 1350);
PAINT SKYBLUE (-7000 1350);
FORCEPROP 1 LAST PACK_TYPE 0402LF
J 0
(-7000 1150);
DISPLAY 0.489362 (-7000 1150);
PAINT SKYBLUE (-7000 1150);
FORCEPROP 2 LAST CDS_LIB pure_quanta
J 0
(-7025 1300);
DISPLAY INVISIBLE (-7025 1300);
FORCEPROP 1 LAST PATH I300
J 0
(-6975 1475);
DISPLAY 0.978723 (-6975 1475);
PAINT WHITE (-6975 1475);
DISPLAY INVISIBLE (-6975 1475);
FORCEPROP 1 LAST PART_NUMBER TMP_QCS21002JB34
J 0
(-6985 1175);
DISPLAY 0.617021 (-6985 1175);
PAINT SKYBLUE (-6985 1175);
DISPLAY INVISIBLE (-6985 1175);
FORCEADD Q_RES..2
(-7350 1300);
FORCEPROP 1 LAST LOCATION R400
J 0
(-7325 1400);
DISPLAY 0.489362 (-7325 1400);
PAINT SKYBLUE (-7325 1400);
FORCEPROP 2 LAST $SEC 1
J 0
(-7300 1525);
DISPLAY 0.680851 (-7300 1525);
PAINT MONO (-7300 1525);
DISPLAY INVISIBLE (-7300 1525);
FORCEPROP 2 LAST CDS_SEC 1
J 0
(-7300 1525);
DISPLAY 1.021277 (-7300 1525);
DISPLAY INVISIBLE (-7300 1525);
FORCEPROP 1 LASTPIN (-7350 1400) $PN 1
J 0
(-7345 1362);
DISPLAY 0.489362 (-7345 1362);
FORCEPROP 1 LASTPIN (-7350 1200) $PN 2
J 0
(-7345 1210);
DISPLAY 0.489362 (-7345 1210);
FORCEPROP 1 LAST WATTAGE 1/16W
J 0
(-7325 1250);
DISPLAY 0.489362 (-7325 1250);
PAINT SKYBLUE (-7325 1250);
FORCEPROP 1 LAST MATERIAL CHIP
J 0
(-7325 1200);
DISPLAY 0.489362 (-7325 1200);
PAINT SKYBLUE (-7325 1200);
FORCEPROP 1 LAST TOLERANCE 5%
J 0
(-7325 1300);
DISPLAY 0.489362 (-7325 1300);
PAINT SKYBLUE (-7325 1300);
FORCEPROP 1 LAST VALUE 1K
J 0
(-7325 1350);
DISPLAY 0.489362 (-7325 1350);
PAINT SKYBLUE (-7325 1350);
FORCEPROP 1 LAST PACK_TYPE 0402LF
J 0
(-7325 1150);
DISPLAY 0.489362 (-7325 1150);
PAINT SKYBLUE (-7325 1150);
FORCEPROP 2 LAST CDS_LIB pure_quanta
J 0
(-7350 1300);
DISPLAY INVISIBLE (-7350 1300);
FORCEPROP 1 LAST PATH I301
J 0
(-7300 1475);
DISPLAY 0.978723 (-7300 1475);
PAINT WHITE (-7300 1475);
DISPLAY INVISIBLE (-7300 1475);
FORCEPROP 1 LAST PART_NUMBER TMP_QCS21002JB34
J 0
(-7310 1175);
DISPLAY 0.617021 (-7310 1175);
PAINT SKYBLUE (-7310 1175);
DISPLAY INVISIBLE (-7310 1175);
FORCEADD Q_CAP..1
(-7025 600);
FORCEPROP 1 LAST LOCATION C210
J 0
(-6975 700);
DISPLAY 0.489362 (-6975 700);
PAINT SKYBLUE (-6975 700);
FORCEPROP 0 LAST $SEC 1
J 0
(-6975 750);
PAINT MONO (-6975 750);
DISPLAY INVISIBLE (-6975 750);
FORCEPROP 0 LAST CDS_SEC 1
J 0
(-6975 750);
PAINT MONO (-6975 750);
DISPLAY INVISIBLE (-6975 750);
FORCEPROP 1 LASTPIN (-7025 700) $PN 1
J 0
(-7015 680);
DISPLAY 0.489362 (-7015 680);
PAINT GREEN (-7015 680);
FORCEPROP 1 LASTPIN (-7025 500) $PN 2
J 0
(-7015 480);
DISPLAY 0.489362 (-7015 480);
PAINT GREEN (-7015 480);
FORCEPROP 1 LAST MATERIAL EMPTY
J 0
(-6975 400);
DISPLAY 0.489362 (-6975 400);
PAINT RED (-6975 400);
FORCEPROP 1 LAST TOLERANCE 10%
J 0
(-6975 550);
DISPLAY 0.489362 (-6975 550);
PAINT SKYBLUE (-6975 550);
FORCEPROP 1 LAST VALUE 0.001UF
J 0
(-6975 650);
DISPLAY 0.489362 (-6975 650);
PAINT SKYBLUE (-6975 650);
FORCEPROP 1 LAST VOLTAGE 50V
J 0
(-6975 600);
DISPLAY 0.489362 (-6975 600);
PAINT SKYBLUE (-6975 600);
FORCEPROP 1 LAST PACK_TYPE C0402
J 0
(-6975 450);
DISPLAY 0.489362 (-6975 450);
PAINT SKYBLUE (-6975 450);
FORCEPROP 2 LAST CDS_LIB pure_quanta
J 0
(-7025 600);
PAINT MONO (-7025 600);
DISPLAY INVISIBLE (-7025 600);
FORCEPROP 1 LAST PATH I302
J 0
(-6975 750);
DISPLAY 0.978723 (-6975 750);
PAINT WHITE (-6975 750);
DISPLAY INVISIBLE (-6975 750);
FORCEPROP 1 LAST PART_NUMBER CH30106KB19
J 0
(-6975 500);
DISPLAY 0.808511 (-6975 500);
PAINT SKYBLUE (-6975 500);
DISPLAY INVISIBLE (-6975 500);
FORCEADD Q_CAP..1
(-7350 600);
FORCEPROP 1 LAST LOCATION C209
J 0
(-7300 700);
DISPLAY 0.489362 (-7300 700);
PAINT SKYBLUE (-7300 700);
FORCEPROP 0 LAST $SEC 1
J 0
(-7300 750);
PAINT MONO (-7300 750);
DISPLAY INVISIBLE (-7300 750);
FORCEPROP 0 LAST CDS_SEC 1
J 0
(-7300 750);
PAINT MONO (-7300 750);
DISPLAY INVISIBLE (-7300 750);
FORCEPROP 1 LASTPIN (-7350 700) $PN 1
J 0
(-7340 680);
DISPLAY 0.489362 (-7340 680);
PAINT GREEN (-7340 680);
FORCEPROP 1 LASTPIN (-7350 500) $PN 2
J 0
(-7340 480);
DISPLAY 0.489362 (-7340 480);
PAINT GREEN (-7340 480);
FORCEPROP 1 LAST MATERIAL EMPTY
J 0
(-7300 400);
DISPLAY 0.489362 (-7300 400);
PAINT RED (-7300 400);
FORCEPROP 1 LAST TOLERANCE 10%
J 0
(-7300 550);
DISPLAY 0.489362 (-7300 550);
PAINT SKYBLUE (-7300 550);
FORCEPROP 1 LAST VALUE 0.001UF
J 0
(-7300 650);
DISPLAY 0.489362 (-7300 650);
PAINT SKYBLUE (-7300 650);
FORCEPROP 1 LAST VOLTAGE 50V
J 0
(-7300 600);
DISPLAY 0.489362 (-7300 600);
PAINT SKYBLUE (-7300 600);
FORCEPROP 1 LAST PACK_TYPE C0402
J 0
(-7300 450);
DISPLAY 0.489362 (-7300 450);
PAINT SKYBLUE (-7300 450);
FORCEPROP 2 LAST CDS_LIB pure_quanta
J 0
(-7350 600);
PAINT MONO (-7350 600);
DISPLAY INVISIBLE (-7350 600);
FORCEPROP 1 LAST PATH I303
J 0
(-7300 750);
DISPLAY 0.978723 (-7300 750);
PAINT WHITE (-7300 750);
DISPLAY INVISIBLE (-7300 750);
FORCEPROP 1 LAST PART_NUMBER CH30106KB19
J 0
(-7300 500);
DISPLAY 0.808511 (-7300 500);
PAINT SKYBLUE (-7300 500);
DISPLAY INVISIBLE (-7300 500);
FORCEADD Q_RES..2
(-7675 1300);
FORCEPROP 1 LAST LOCATION R399
J 0
(-7650 1400);
DISPLAY 0.489362 (-7650 1400);
PAINT SKYBLUE (-7650 1400);
FORCEPROP 2 LAST $SEC 1
J 0
(-7625 1525);
DISPLAY 0.680851 (-7625 1525);
PAINT MONO (-7625 1525);
DISPLAY INVISIBLE (-7625 1525);
FORCEPROP 2 LAST CDS_SEC 1
J 0
(-7625 1525);
DISPLAY 1.021277 (-7625 1525);
DISPLAY INVISIBLE (-7625 1525);
FORCEPROP 1 LASTPIN (-7675 1400) $PN 1
J 0
(-7670 1362);
DISPLAY 0.489362 (-7670 1362);
FORCEPROP 1 LASTPIN (-7675 1200) $PN 2
J 0
(-7670 1210);
DISPLAY 0.489362 (-7670 1210);
FORCEPROP 1 LAST WATTAGE 1/16W
J 0
(-7650 1250);
DISPLAY 0.489362 (-7650 1250);
PAINT SKYBLUE (-7650 1250);
FORCEPROP 1 LAST MATERIAL CHIP
J 0
(-7650 1200);
DISPLAY 0.489362 (-7650 1200);
PAINT SKYBLUE (-7650 1200);
FORCEPROP 1 LAST TOLERANCE 5%
J 0
(-7650 1300);
DISPLAY 0.489362 (-7650 1300);
PAINT SKYBLUE (-7650 1300);
FORCEPROP 1 LAST VALUE 1K
J 0
(-7650 1350);
DISPLAY 0.489362 (-7650 1350);
PAINT SKYBLUE (-7650 1350);
FORCEPROP 1 LAST PACK_TYPE 0402LF
J 0
(-7650 1150);
DISPLAY 0.489362 (-7650 1150);
PAINT SKYBLUE (-7650 1150);
FORCEPROP 2 LAST CDS_LIB pure_quanta
J 0
(-7675 1300);
DISPLAY INVISIBLE (-7675 1300);
FORCEPROP 1 LAST PATH I304
J 0
(-7625 1475);
DISPLAY 0.978723 (-7625 1475);
PAINT WHITE (-7625 1475);
DISPLAY INVISIBLE (-7625 1475);
FORCEPROP 1 LAST PART_NUMBER TMP_QCS21002JB34
J 0
(-7635 1175);
DISPLAY 0.617021 (-7635 1175);
PAINT SKYBLUE (-7635 1175);
DISPLAY INVISIBLE (-7635 1175);
FORCEADD Q_RES..2
(-8000 1300);
FORCEPROP 1 LAST LOCATION R398
J 0
(-7975 1400);
DISPLAY 0.489362 (-7975 1400);
PAINT SKYBLUE (-7975 1400);
FORCEPROP 2 LAST $SEC 1
J 0
(-7950 1525);
DISPLAY 0.680851 (-7950 1525);
PAINT MONO (-7950 1525);
DISPLAY INVISIBLE (-7950 1525);
FORCEPROP 2 LAST CDS_SEC 1
J 0
(-7950 1525);
DISPLAY 1.021277 (-7950 1525);
DISPLAY INVISIBLE (-7950 1525);
FORCEPROP 1 LASTPIN (-8000 1400) $PN 1
J 0
(-7995 1362);
DISPLAY 0.489362 (-7995 1362);
FORCEPROP 1 LASTPIN (-8000 1200) $PN 2
J 0
(-7995 1210);
DISPLAY 0.489362 (-7995 1210);
FORCEPROP 1 LAST WATTAGE 1/16W
J 0
(-7975 1250);
DISPLAY 0.489362 (-7975 1250);
PAINT SKYBLUE (-7975 1250);
FORCEPROP 1 LAST MATERIAL CHIP
J 0
(-7975 1200);
DISPLAY 0.489362 (-7975 1200);
PAINT SKYBLUE (-7975 1200);
FORCEPROP 1 LAST TOLERANCE 5%
J 0
(-7975 1300);
DISPLAY 0.489362 (-7975 1300);
PAINT SKYBLUE (-7975 1300);
FORCEPROP 1 LAST VALUE 1K
J 0
(-7975 1350);
DISPLAY 0.489362 (-7975 1350);
PAINT SKYBLUE (-7975 1350);
FORCEPROP 1 LAST PACK_TYPE 0402LF
J 0
(-7975 1150);
DISPLAY 0.489362 (-7975 1150);
PAINT SKYBLUE (-7975 1150);
FORCEPROP 2 LAST CDS_LIB pure_quanta
J 0
(-8000 1300);
DISPLAY INVISIBLE (-8000 1300);
FORCEPROP 1 LAST PATH I305
J 0
(-7950 1475);
DISPLAY 0.978723 (-7950 1475);
PAINT WHITE (-7950 1475);
DISPLAY INVISIBLE (-7950 1475);
FORCEPROP 1 LAST PART_NUMBER TMP_QCS21002JB34
J 0
(-7960 1175);
DISPLAY 0.617021 (-7960 1175);
PAINT SKYBLUE (-7960 1175);
DISPLAY INVISIBLE (-7960 1175);
FORCEADD Q_CAP..1
(-7675 600);
FORCEPROP 1 LAST LOCATION C208
J 0
(-7625 700);
DISPLAY 0.489362 (-7625 700);
PAINT SKYBLUE (-7625 700);
FORCEPROP 0 LAST $SEC 1
J 0
(-7625 750);
PAINT MONO (-7625 750);
DISPLAY INVISIBLE (-7625 750);
FORCEPROP 0 LAST CDS_SEC 1
J 0
(-7625 750);
PAINT MONO (-7625 750);
DISPLAY INVISIBLE (-7625 750);
FORCEPROP 1 LASTPIN (-7675 700) $PN 1
J 0
(-7665 680);
DISPLAY 0.489362 (-7665 680);
PAINT GREEN (-7665 680);
FORCEPROP 1 LASTPIN (-7675 500) $PN 2
J 0
(-7665 480);
DISPLAY 0.489362 (-7665 480);
PAINT GREEN (-7665 480);
FORCEPROP 1 LAST MATERIAL EMPTY
J 0
(-7625 400);
DISPLAY 0.489362 (-7625 400);
PAINT RED (-7625 400);
FORCEPROP 1 LAST TOLERANCE 10%
J 0
(-7625 550);
DISPLAY 0.489362 (-7625 550);
PAINT SKYBLUE (-7625 550);
FORCEPROP 1 LAST VALUE 0.001UF
J 0
(-7625 650);
DISPLAY 0.489362 (-7625 650);
PAINT SKYBLUE (-7625 650);
FORCEPROP 1 LAST VOLTAGE 50V
J 0
(-7625 600);
DISPLAY 0.489362 (-7625 600);
PAINT SKYBLUE (-7625 600);
FORCEPROP 1 LAST PACK_TYPE C0402
J 0
(-7625 450);
DISPLAY 0.489362 (-7625 450);
PAINT SKYBLUE (-7625 450);
FORCEPROP 2 LAST CDS_LIB pure_quanta
J 0
(-7675 600);
PAINT MONO (-7675 600);
DISPLAY INVISIBLE (-7675 600);
FORCEPROP 1 LAST PATH I306
J 0
(-7625 750);
DISPLAY 0.978723 (-7625 750);
PAINT WHITE (-7625 750);
DISPLAY INVISIBLE (-7625 750);
FORCEPROP 1 LAST PART_NUMBER CH30106KB19
J 0
(-7625 500);
DISPLAY 0.808511 (-7625 500);
PAINT SKYBLUE (-7625 500);
DISPLAY INVISIBLE (-7625 500);
FORCEADD Q_CAP..1
(-8000 600);
FORCEPROP 1 LAST LOCATION C207
J 0
(-7950 700);
DISPLAY 0.489362 (-7950 700);
PAINT SKYBLUE (-7950 700);
FORCEPROP 0 LAST $SEC 1
J 0
(-7950 750);
PAINT MONO (-7950 750);
DISPLAY INVISIBLE (-7950 750);
FORCEPROP 0 LAST CDS_SEC 1
J 0
(-7950 750);
PAINT MONO (-7950 750);
DISPLAY INVISIBLE (-7950 750);
FORCEPROP 1 LASTPIN (-8000 700) $PN 1
J 0
(-7990 680);
DISPLAY 0.489362 (-7990 680);
PAINT GREEN (-7990 680);
FORCEPROP 1 LASTPIN (-8000 500) $PN 2
J 0
(-7990 480);
DISPLAY 0.489362 (-7990 480);
PAINT GREEN (-7990 480);
FORCEPROP 1 LAST MATERIAL EMPTY
J 0
(-7950 400);
DISPLAY 0.489362 (-7950 400);
PAINT RED (-7950 400);
FORCEPROP 1 LAST TOLERANCE 10%
J 0
(-7950 550);
DISPLAY 0.489362 (-7950 550);
PAINT SKYBLUE (-7950 550);
FORCEPROP 1 LAST VALUE 0.001UF
J 0
(-7950 650);
DISPLAY 0.489362 (-7950 650);
PAINT SKYBLUE (-7950 650);
FORCEPROP 1 LAST VOLTAGE 50V
J 0
(-7950 600);
DISPLAY 0.489362 (-7950 600);
PAINT SKYBLUE (-7950 600);
FORCEPROP 1 LAST PACK_TYPE C0402
J 0
(-7950 450);
DISPLAY 0.489362 (-7950 450);
PAINT SKYBLUE (-7950 450);
FORCEPROP 2 LAST CDS_LIB pure_quanta
J 0
(-8000 600);
PAINT MONO (-8000 600);
DISPLAY INVISIBLE (-8000 600);
FORCEPROP 1 LAST PATH I307
J 0
(-7950 750);
DISPLAY 0.978723 (-7950 750);
PAINT WHITE (-7950 750);
DISPLAY INVISIBLE (-7950 750);
FORCEPROP 1 LAST PART_NUMBER CH30106KB19
J 0
(-7950 500);
DISPLAY 0.808511 (-7950 500);
PAINT SKYBLUE (-7950 500);
DISPLAY INVISIBLE (-7950 500);
FORCEADD GND..1
(-7350 300);
FORCEPROP 3 LASTPIN (-7350 350) SIG_NAME GND\g
J 0
(-7340 360);
DISPLAY 0.659574 (-7340 360);
PAINT MONO (-7340 360);
DISPLAY INVISIBLE (-7340 360);
FORCEPROP 1 LAST SIZE 1B
J 0
(-7275 250);
DISPLAY 0.872340 (-7275 250);
PAINT GREEN (-7275 250);
DISPLAY INVISIBLE (-7275 250);
FORCEPROP 2 LAST CDS_LIB pure_quanta_power
J 0
(-7350 300);
DISPLAY INVISIBLE (-7350 300);
FORCEPROP 1 LAST PATH I308
J 0
(-7275 300);
DISPLAY 0.872340 (-7275 300);
PAINT AQUA (-7275 300);
DISPLAY INVISIBLE (-7275 300);
FORCEPROP 1 LAST HDL_POWER GND
J 0
(-7350 450);
DISPLAY 0.872340 (-7350 450);
PAINT GREEN (-7350 450);
DISPLAY INVISIBLE (-7350 450);
FORCEADD GND..1
(-7025 300);
FORCEPROP 3 LASTPIN (-7025 350) SIG_NAME GND\g
J 0
(-7015 360);
DISPLAY 0.659574 (-7015 360);
PAINT MONO (-7015 360);
DISPLAY INVISIBLE (-7015 360);
FORCEPROP 1 LAST SIZE 1B
J 0
(-6950 250);
DISPLAY 0.872340 (-6950 250);
PAINT GREEN (-6950 250);
DISPLAY INVISIBLE (-6950 250);
FORCEPROP 2 LAST CDS_LIB pure_quanta_power
J 0
(-7025 300);
DISPLAY INVISIBLE (-7025 300);
FORCEPROP 1 LAST PATH I309
J 0
(-6950 300);
DISPLAY 0.872340 (-6950 300);
PAINT AQUA (-6950 300);
DISPLAY INVISIBLE (-6950 300);
FORCEPROP 1 LAST HDL_POWER GND
J 0
(-7025 450);
DISPLAY 0.872340 (-7025 450);
PAINT GREEN (-7025 450);
DISPLAY INVISIBLE (-7025 450);
FORCEADD GND..1
(-8000 300);
FORCEPROP 3 LASTPIN (-8000 350) SIG_NAME GND\g
J 0
(-7990 360);
DISPLAY 0.659574 (-7990 360);
PAINT MONO (-7990 360);
DISPLAY INVISIBLE (-7990 360);
FORCEPROP 1 LAST SIZE 1B
J 0
(-7925 250);
DISPLAY 0.872340 (-7925 250);
PAINT GREEN (-7925 250);
DISPLAY INVISIBLE (-7925 250);
FORCEPROP 2 LAST CDS_LIB pure_quanta_power
J 0
(-8000 300);
DISPLAY INVISIBLE (-8000 300);
FORCEPROP 1 LAST PATH I310
J 0
(-7925 300);
DISPLAY 0.872340 (-7925 300);
PAINT AQUA (-7925 300);
DISPLAY INVISIBLE (-7925 300);
FORCEPROP 1 LAST HDL_POWER GND
J 0
(-8000 450);
DISPLAY 0.872340 (-8000 450);
PAINT GREEN (-8000 450);
DISPLAY INVISIBLE (-8000 450);
FORCEADD GND..1
(-7675 300);
FORCEPROP 3 LASTPIN (-7675 350) SIG_NAME GND\g
J 0
(-7665 360);
DISPLAY 0.659574 (-7665 360);
PAINT MONO (-7665 360);
DISPLAY INVISIBLE (-7665 360);
FORCEPROP 2 LAST CDS_LIB pure_quanta_power
J 0
(-7675 300);
DISPLAY INVISIBLE (-7675 300);
FORCEPROP 1 LAST SIZE 1B
J 0
(-7600 250);
DISPLAY 0.872340 (-7600 250);
PAINT GREEN (-7600 250);
DISPLAY INVISIBLE (-7600 250);
FORCEPROP 1 LAST PATH I311
J 0
(-7600 300);
DISPLAY 0.872340 (-7600 300);
PAINT AQUA (-7600 300);
DISPLAY INVISIBLE (-7600 300);
FORCEPROP 1 LAST HDL_POWER GND
J 0
(-7675 450);
DISPLAY 0.872340 (-7675 450);
PAINT GREEN (-7675 450);
DISPLAY INVISIBLE (-7675 450);
FORCEADD OFFPAGE..2
R 2
(-8775 1100);
FORCEPROP 2 LAST $XR1 151 
J 0
(-9119 1100);
DISPLAY 0.638298 (-9119 1100);
PAINT MONO (-9119 1100);
FORCEPROP 2 LAST $XR0 27 
J 0
(-8999 1100);
DISPLAY 0.638298 (-8999 1100);
PAINT MONO (-8999 1100);
FORCEPROP 2 LAST CDS_LIB standard
J 2
(-8775 1100);
DISPLAY INVISIBLE (-8775 1100);
FORCEPROP 1 LAST OFFPAGE TRUE
J 2
(-9100 975);
DISPLAY 0.872340 (-9100 975);
PAINT GREEN (-9100 975);
DISPLAY INVISIBLE (-9100 975);
FORCEPROP 1 LAST COMMENT_BODY TRUE
J 2
(-8730 1005);
DISPLAY 0.872340 (-8730 1005);
PAINT GREEN (-8730 1005);
DISPLAY INVISIBLE (-8730 1005);
FORCEPROP 2 LAST PATH I312
J 0
(-9025 1150);
DISPLAY 0.680851 (-9025 1150);
DISPLAY INVISIBLE (-9025 1150);
FORCEADD OFFPAGE..2
R 2
(-8775 1000);
FORCEPROP 2 LAST $XR1 27 
J 0
(-9120 1000);
DISPLAY 0.638298 (-9120 1000);
PAINT MONO (-9120 1000);
FORCEPROP 2 LAST $XR0 150 
J 0
(-9030 1000);
DISPLAY 0.638298 (-9030 1000);
PAINT MONO (-9030 1000);
FORCEPROP 2 LAST CDS_LIB standard
J 0
(-8775 1000);
DISPLAY INVISIBLE (-8775 1000);
FORCEPROP 1 LAST OFFPAGE TRUE
J 2
(-9100 875);
DISPLAY 0.872340 (-9100 875);
PAINT GREEN (-9100 875);
DISPLAY INVISIBLE (-9100 875);
FORCEPROP 1 LAST COMMENT_BODY TRUE
J 2
(-8730 905);
DISPLAY 0.872340 (-8730 905);
PAINT GREEN (-8730 905);
DISPLAY INVISIBLE (-8730 905);
FORCEPROP 2 LAST PATH I313
J 0
(-9025 1050);
DISPLAY 0.680851 (-9025 1050);
DISPLAY INVISIBLE (-9025 1050);
FORCEADD OFFPAGE..2
R 2
(-8775 1050);
FORCEPROP 2 LAST $XR1 27 
J 0
(-9120 1050);
DISPLAY 0.638298 (-9120 1050);
PAINT MONO (-9120 1050);
FORCEPROP 2 LAST $XR0 151 
J 0
(-9030 1050);
DISPLAY 0.638298 (-9030 1050);
PAINT MONO (-9030 1050);
FORCEPROP 2 LAST CDS_LIB standard
J 0
(-8775 1050);
DISPLAY INVISIBLE (-8775 1050);
FORCEPROP 1 LAST OFFPAGE TRUE
J 2
(-9100 925);
DISPLAY 0.872340 (-9100 925);
PAINT GREEN (-9100 925);
DISPLAY INVISIBLE (-9100 925);
FORCEPROP 1 LAST COMMENT_BODY TRUE
J 2
(-8730 955);
DISPLAY 0.872340 (-8730 955);
PAINT GREEN (-8730 955);
DISPLAY INVISIBLE (-8730 955);
FORCEPROP 2 LAST PATH I314
J 0
(-9025 1100);
DISPLAY 0.680851 (-9025 1100);
DISPLAY INVISIBLE (-9025 1100);
FORCEADD OFFPAGE..2
R 2
(-8775 900);
FORCEPROP 2 LAST $XR1 27 
J 0
(-9120 900);
DISPLAY 0.638298 (-9120 900);
PAINT MONO (-9120 900);
FORCEPROP 2 LAST $XR0 150 
J 0
(-9030 900);
DISPLAY 0.638298 (-9030 900);
PAINT MONO (-9030 900);
FORCEPROP 2 LAST CDS_LIB standard
J 0
(-8775 900);
DISPLAY INVISIBLE (-8775 900);
FORCEPROP 1 LAST OFFPAGE TRUE
J 2
(-9100 775);
DISPLAY 0.872340 (-9100 775);
PAINT GREEN (-9100 775);
DISPLAY INVISIBLE (-9100 775);
FORCEPROP 1 LAST COMMENT_BODY TRUE
J 2
(-8730 805);
DISPLAY 0.872340 (-8730 805);
PAINT GREEN (-8730 805);
DISPLAY INVISIBLE (-8730 805);
FORCEPROP 2 LAST PATH I315
J 0
(-9025 950);
DISPLAY 0.680851 (-9025 950);
DISPLAY INVISIBLE (-9025 950);
FORCEADD OFFPAGE..2
R 2
(-8775 950);
FORCEPROP 2 LAST $XR1 27 
J 0
(-9120 950);
DISPLAY 0.638298 (-9120 950);
PAINT MONO (-9120 950);
FORCEPROP 2 LAST $XR0 150 
J 0
(-9030 950);
DISPLAY 0.638298 (-9030 950);
PAINT MONO (-9030 950);
FORCEPROP 2 LAST CDS_LIB standard
J 0
(-8775 950);
DISPLAY INVISIBLE (-8775 950);
FORCEPROP 1 LAST OFFPAGE TRUE
J 2
(-9100 825);
DISPLAY 0.872340 (-9100 825);
PAINT GREEN (-9100 825);
DISPLAY INVISIBLE (-9100 825);
FORCEPROP 1 LAST COMMENT_BODY TRUE
J 2
(-8730 855);
DISPLAY 0.872340 (-8730 855);
PAINT GREEN (-8730 855);
DISPLAY INVISIBLE (-8730 855);
FORCEPROP 2 LAST PATH I316
J 0
(-9025 1000);
DISPLAY 0.680851 (-9025 1000);
DISPLAY INVISIBLE (-9025 1000);
FORCEADD OFFPAGE..2
R 2
(-8775 850);
FORCEPROP 2 LAST $XR1 27 
J 0
(-9120 850);
DISPLAY 0.638298 (-9120 850);
PAINT MONO (-9120 850);
FORCEPROP 2 LAST $XR0 150 
J 0
(-9030 850);
DISPLAY 0.638298 (-9030 850);
PAINT MONO (-9030 850);
FORCEPROP 2 LAST CDS_LIB standard
J 0
(-8775 850);
DISPLAY INVISIBLE (-8775 850);
FORCEPROP 1 LAST OFFPAGE TRUE
J 2
(-9100 725);
DISPLAY 0.872340 (-9100 725);
PAINT GREEN (-9100 725);
DISPLAY INVISIBLE (-9100 725);
FORCEPROP 1 LAST COMMENT_BODY TRUE
J 2
(-8730 755);
DISPLAY 0.872340 (-8730 755);
PAINT GREEN (-8730 755);
DISPLAY INVISIBLE (-8730 755);
FORCEPROP 2 LAST PATH I317
J 0
(-9025 900);
DISPLAY 0.680851 (-9025 900);
DISPLAY INVISIBLE (-9025 900);
FORCEADD Q_RES..1
(-6350 5325);
FORCEPROP 1 LAST LOCATION PR59
J 0
(-6550 5325);
DISPLAY 0.489362 (-6550 5325);
PAINT SKYBLUE (-6550 5325);
FORCEPROP 0 LAST $SEC 1
J 0
(-5950 5450);
DISPLAY 0.680851 (-5950 5450);
PAINT MONO (-5950 5450);
DISPLAY INVISIBLE (-5950 5450);
FORCEPROP 0 LAST CDS_SEC 1
J 0
(-5950 5450);
DISPLAY 1.021277 (-5950 5450);
DISPLAY INVISIBLE (-5950 5450);
FORCEPROP 1 LASTPIN (-6450 5325) $PN 1
J 0
(-6438 5337);
DISPLAY 0.489362 (-6438 5337);
PAINT MONO (-6438 5337);
FORCEPROP 1 LASTPIN (-6250 5325) $PN 2
J 0
(-6288 5337);
DISPLAY 0.489362 (-6288 5337);
PAINT MONO (-6288 5337);
FORCEPROP 1 LAST VALUE 0
J 2
(-6200 5325);
DISPLAY 0.489362 (-6200 5325);
PAINT SKYBLUE (-6200 5325);
FORCEPROP 2 LAST CDS_LIB pure_quanta
J 0
(-6350 5325);
DISPLAY INVISIBLE (-6350 5325);
FORCEPROP 1 LAST PATH I318
J 0
(-6400 5475);
DISPLAY 0.978723 (-6400 5475);
PAINT WHITE (-6400 5475);
DISPLAY INVISIBLE (-6400 5475);
FORCEPROP 1 LAST WATTAGE 1/16W
J 2
(-5950 5425);
DISPLAY 0.489362 (-5950 5425);
PAINT SKYBLUE (-5950 5425);
DISPLAY INVISIBLE (-5950 5425);
FORCEPROP 1 LAST MATERIAL CHIP
J 0
(-6225 5425);
DISPLAY 0.489362 (-6225 5425);
PAINT SKYBLUE (-6225 5425);
DISPLAY INVISIBLE (-6225 5425);
FORCEPROP 1 LAST TOLERANCE 5%
J 0
(-5825 5375);
DISPLAY 0.489362 (-5825 5375);
PAINT SKYBLUE (-5825 5375);
DISPLAY INVISIBLE (-5825 5375);
FORCEPROP 1 LAST PART_NUMBER CS00002JB38
J 0
(-6225 5375);
DISPLAY 0.489362 (-6225 5375);
PAINT SKYBLUE (-6225 5375);
DISPLAY INVISIBLE (-6225 5375);
FORCEPROP 1 LAST PACK_TYPE 0402LF
J 0
(-5750 5375);
DISPLAY 0.489362 (-5750 5375);
PAINT SKYBLUE (-5750 5375);
DISPLAY INVISIBLE (-5750 5375);
FORCEADD Q_RES..1
(-6350 5275);
FORCEPROP 1 LAST LOCATION PR60
J 0
(-6550 5275);
DISPLAY 0.489362 (-6550 5275);
PAINT SKYBLUE (-6550 5275);
FORCEPROP 0 LAST $SEC 1
J 0
(-6400 5375);
DISPLAY 0.680851 (-6400 5375);
PAINT MONO (-6400 5375);
DISPLAY INVISIBLE (-6400 5375);
FORCEPROP 0 LAST CDS_SEC 1
J 0
(-6400 5375);
DISPLAY 1.021277 (-6400 5375);
DISPLAY INVISIBLE (-6400 5375);
FORCEPROP 1 LASTPIN (-6450 5275) $PN 1
J 0
(-6438 5287);
DISPLAY 0.489362 (-6438 5287);
PAINT MONO (-6438 5287);
FORCEPROP 1 LASTPIN (-6250 5275) $PN 2
J 0
(-6288 5287);
DISPLAY 0.489362 (-6288 5287);
PAINT MONO (-6288 5287);
FORCEPROP 1 LAST VALUE 0
J 2
(-6200 5275);
DISPLAY 0.489362 (-6200 5275);
PAINT SKYBLUE (-6200 5275);
FORCEPROP 2 LAST CDS_LIB pure_quanta
J 0
(-6350 5275);
DISPLAY INVISIBLE (-6350 5275);
FORCEPROP 1 LAST PATH I319
J 0
(-6400 5425);
DISPLAY 0.978723 (-6400 5425);
PAINT WHITE (-6400 5425);
DISPLAY INVISIBLE (-6400 5425);
FORCEPROP 1 LAST WATTAGE 1/16W
J 2
(-5950 5375);
DISPLAY 0.489362 (-5950 5375);
PAINT SKYBLUE (-5950 5375);
DISPLAY INVISIBLE (-5950 5375);
FORCEPROP 1 LAST MATERIAL CHIP
J 0
(-6225 5375);
DISPLAY 0.489362 (-6225 5375);
PAINT SKYBLUE (-6225 5375);
DISPLAY INVISIBLE (-6225 5375);
FORCEPROP 1 LAST TOLERANCE 5%
J 0
(-5825 5325);
DISPLAY 0.489362 (-5825 5325);
PAINT SKYBLUE (-5825 5325);
DISPLAY INVISIBLE (-5825 5325);
FORCEPROP 1 LAST PART_NUMBER CS00002JB38
J 0
(-6225 5325);
DISPLAY 0.489362 (-6225 5325);
PAINT SKYBLUE (-6225 5325);
DISPLAY INVISIBLE (-6225 5325);
FORCEPROP 1 LAST PACK_TYPE 0402LF
J 0
(-5750 5325);
DISPLAY 0.489362 (-5750 5325);
PAINT SKYBLUE (-5750 5325);
DISPLAY INVISIBLE (-5750 5325);
FORCEADD OFFPAGE..2
R 2
(-7525 5275);
FORCEPROP 2 LAST $XR0 176 
J 0
(-7810 5275);
DISPLAY 0.638298 (-7810 5275);
PAINT MONO (-7810 5275);
FORCEPROP 2 LAST CDS_LIB standard
J 0
(-7525 5275);
DISPLAY INVISIBLE (-7525 5275);
FORCEPROP 1 LAST OFFPAGE TRUE
J 2
(-7850 5150);
DISPLAY 0.872340 (-7850 5150);
PAINT GREEN (-7850 5150);
DISPLAY INVISIBLE (-7850 5150);
FORCEPROP 1 LAST COMMENT_BODY TRUE
J 2
(-7480 5180);
DISPLAY 0.872340 (-7480 5180);
PAINT GREEN (-7480 5180);
DISPLAY INVISIBLE (-7480 5180);
FORCEPROP 2 LAST PATH I320
J 0
(-7475 5350);
DISPLAY 0.680851 (-7475 5350);
DISPLAY INVISIBLE (-7475 5350);
FORCEADD OFFPAGE..2
R 2
(-7525 5325);
FORCEPROP 2 LAST $XR0 176 
J 0
(-7810 5325);
DISPLAY 0.638298 (-7810 5325);
PAINT MONO (-7810 5325);
FORCEPROP 2 LAST CDS_LIB standard
J 0
(-7525 5325);
DISPLAY INVISIBLE (-7525 5325);
FORCEPROP 1 LAST OFFPAGE TRUE
J 2
(-7850 5200);
DISPLAY 0.872340 (-7850 5200);
PAINT GREEN (-7850 5200);
DISPLAY INVISIBLE (-7850 5200);
FORCEPROP 1 LAST COMMENT_BODY TRUE
J 2
(-7480 5230);
DISPLAY 0.872340 (-7480 5230);
PAINT GREEN (-7480 5230);
DISPLAY INVISIBLE (-7480 5230);
FORCEPROP 2 LAST PATH I321
J 0
(-7475 5400);
DISPLAY 0.680851 (-7475 5400);
DISPLAY INVISIBLE (-7475 5400);
FORCEADD Q_RES..1
(-6350 5475);
FORCEPROP 1 LAST LOCATION PR303
J 0
(-6575 5475);
DISPLAY 0.489362 (-6575 5475);
PAINT SKYBLUE (-6575 5475);
FORCEPROP 0 LAST $SEC 1
J 0
(-6400 5550);
DISPLAY 0.680851 (-6400 5550);
PAINT MONO (-6400 5550);
DISPLAY INVISIBLE (-6400 5550);
FORCEPROP 0 LAST CDS_SEC 1
J 0
(-6400 5550);
DISPLAY 1.021277 (-6400 5550);
DISPLAY INVISIBLE (-6400 5550);
FORCEPROP 1 LASTPIN (-6450 5475) $PN 1
J 0
(-6438 5487);
DISPLAY 0.489362 (-6438 5487);
PAINT MONO (-6438 5487);
FORCEPROP 1 LASTPIN (-6250 5475) $PN 2
J 0
(-6288 5487);
DISPLAY 0.489362 (-6288 5487);
PAINT MONO (-6288 5487);
FORCEPROP 1 LAST VALUE 0
J 2
(-6175 5475);
DISPLAY 0.489362 (-6175 5475);
PAINT SKYBLUE (-6175 5475);
FORCEPROP 2 LAST CDS_LIB pure_quanta
J 0
(-6350 5475);
DISPLAY INVISIBLE (-6350 5475);
FORCEPROP 1 LAST PATH I322
J 0
(-6400 5625);
DISPLAY 0.978723 (-6400 5625);
PAINT WHITE (-6400 5625);
DISPLAY INVISIBLE (-6400 5625);
FORCEPROP 1 LAST WATTAGE 1/16W
J 0
(-6250 5425);
DISPLAY 0.489362 (-6250 5425);
PAINT SKYBLUE (-6250 5425);
DISPLAY INVISIBLE (-6250 5425);
FORCEPROP 1 LAST MATERIAL CHIP
J 0
(-6600 5400);
DISPLAY 0.489362 (-6600 5400);
PAINT SKYBLUE (-6600 5400);
DISPLAY INVISIBLE (-6600 5400);
FORCEPROP 1 LAST TOLERANCE 5%
J 0
(-6225 5500);
DISPLAY 0.489362 (-6225 5500);
PAINT SKYBLUE (-6225 5500);
DISPLAY INVISIBLE (-6225 5500);
FORCEPROP 1 LAST PART_NUMBER CS00002JB38
J 0
(-6600 5425);
DISPLAY 0.489362 (-6600 5425);
PAINT SKYBLUE (-6600 5425);
DISPLAY INVISIBLE (-6600 5425);
FORCEPROP 1 LAST PACK_TYPE 0402LF
J 0
(-6250 5400);
DISPLAY 0.489362 (-6250 5400);
PAINT SKYBLUE (-6250 5400);
DISPLAY INVISIBLE (-6250 5400);
FORCEADD Q_RES..1
(-6350 5525);
FORCEPROP 1 LAST LOCATION PR302
J 0
(-6575 5525);
DISPLAY 0.489362 (-6575 5525);
PAINT SKYBLUE (-6575 5525);
FORCEPROP 0 LAST $SEC 1
J 0
(-6400 5600);
DISPLAY 0.680851 (-6400 5600);
PAINT MONO (-6400 5600);
DISPLAY INVISIBLE (-6400 5600);
FORCEPROP 0 LAST CDS_SEC 1
J 0
(-6400 5600);
DISPLAY 1.021277 (-6400 5600);
DISPLAY INVISIBLE (-6400 5600);
FORCEPROP 1 LASTPIN (-6450 5525) $PN 1
J 0
(-6438 5537);
DISPLAY 0.489362 (-6438 5537);
PAINT MONO (-6438 5537);
FORCEPROP 1 LASTPIN (-6250 5525) $PN 2
J 0
(-6288 5537);
DISPLAY 0.489362 (-6288 5537);
PAINT MONO (-6288 5537);
FORCEPROP 1 LAST VALUE 0
J 2
(-6175 5525);
DISPLAY 0.489362 (-6175 5525);
PAINT SKYBLUE (-6175 5525);
FORCEPROP 2 LAST CDS_LIB pure_quanta
J 0
(-6350 5525);
DISPLAY INVISIBLE (-6350 5525);
FORCEPROP 1 LAST PATH I323
J 0
(-6400 5675);
DISPLAY 0.978723 (-6400 5675);
PAINT WHITE (-6400 5675);
DISPLAY INVISIBLE (-6400 5675);
FORCEPROP 1 LAST WATTAGE 1/16W
J 0
(-6250 5475);
DISPLAY 0.489362 (-6250 5475);
PAINT SKYBLUE (-6250 5475);
DISPLAY INVISIBLE (-6250 5475);
FORCEPROP 1 LAST MATERIAL CHIP
J 0
(-6600 5450);
DISPLAY 0.489362 (-6600 5450);
PAINT SKYBLUE (-6600 5450);
DISPLAY INVISIBLE (-6600 5450);
FORCEPROP 1 LAST TOLERANCE 5%
J 0
(-6225 5550);
DISPLAY 0.489362 (-6225 5550);
PAINT SKYBLUE (-6225 5550);
DISPLAY INVISIBLE (-6225 5550);
FORCEPROP 1 LAST PART_NUMBER CS00002JB38
J 0
(-6600 5475);
DISPLAY 0.489362 (-6600 5475);
PAINT SKYBLUE (-6600 5475);
DISPLAY INVISIBLE (-6600 5475);
FORCEPROP 1 LAST PACK_TYPE 0402LF
J 0
(-6250 5450);
DISPLAY 0.489362 (-6250 5450);
PAINT SKYBLUE (-6250 5450);
DISPLAY INVISIBLE (-6250 5450);
FORCEADD OFFPAGE..2
R 2
(-7525 5475);
FORCEPROP 2 LAST $XR0 169 
J 0
(-7810 5475);
DISPLAY 0.638298 (-7810 5475);
PAINT MONO (-7810 5475);
FORCEPROP 2 LAST CDS_LIB standard
J 0
(-7525 5475);
DISPLAY INVISIBLE (-7525 5475);
FORCEPROP 1 LAST OFFPAGE TRUE
J 2
(-7850 5350);
DISPLAY 0.872340 (-7850 5350);
PAINT GREEN (-7850 5350);
DISPLAY INVISIBLE (-7850 5350);
FORCEPROP 1 LAST COMMENT_BODY TRUE
J 2
(-7480 5380);
DISPLAY 0.872340 (-7480 5380);
PAINT GREEN (-7480 5380);
DISPLAY INVISIBLE (-7480 5380);
FORCEPROP 2 LAST PATH I324
J 0
(-7475 5550);
DISPLAY 0.680851 (-7475 5550);
DISPLAY INVISIBLE (-7475 5550);
FORCEADD OFFPAGE..2
R 2
(-7525 5525);
FORCEPROP 2 LAST $XR0 169 
J 0
(-7810 5525);
DISPLAY 0.638298 (-7810 5525);
PAINT MONO (-7810 5525);
FORCEPROP 2 LAST CDS_LIB standard
J 0
(-7525 5525);
DISPLAY INVISIBLE (-7525 5525);
FORCEPROP 1 LAST OFFPAGE TRUE
J 2
(-7850 5400);
DISPLAY 0.872340 (-7850 5400);
PAINT GREEN (-7850 5400);
DISPLAY INVISIBLE (-7850 5400);
FORCEPROP 1 LAST COMMENT_BODY TRUE
J 2
(-7480 5430);
DISPLAY 0.872340 (-7480 5430);
PAINT GREEN (-7480 5430);
DISPLAY INVISIBLE (-7480 5430);
FORCEPROP 2 LAST PATH I325
J 0
(-7475 5600);
DISPLAY 0.680851 (-7475 5600);
DISPLAY INVISIBLE (-7475 5600);
FORCEADD Q_RES..1
(-1475 2900);
FORCEPROP 1 LAST LOCATION R483
J 0
(-1375 2900);
DISPLAY 0.489362 (-1375 2900);
PAINT SKYBLUE (-1375 2900);
FORCEPROP 0 LAST $SEC 1
J 0
(-1375 2950);
DISPLAY 0.680851 (-1375 2950);
PAINT MONO (-1375 2950);
DISPLAY INVISIBLE (-1375 2950);
FORCEPROP 0 LAST CDS_SEC 1
J 0
(-1375 2950);
DISPLAY 0.680851 (-1375 2950);
DISPLAY INVISIBLE (-1375 2950);
FORCEPROP 1 LASTPIN (-1575 2900) $PN 1
J 0
(-1563 2912);
DISPLAY 0.489362 (-1563 2912);
PAINT MONO (-1563 2912);
FORCEPROP 1 LASTPIN (-1375 2900) $PN 2
J 0
(-1413 2912);
DISPLAY 0.489362 (-1413 2912);
PAINT MONO (-1413 2912);
FORCEPROP 1 LAST VALUE 0
J 2
(-1575 2900);
DISPLAY 0.489362 (-1575 2900);
PAINT SKYBLUE (-1575 2900);
FORCEPROP 2 LAST CDS_LIB pure_quanta
J 0
(-1475 2900);
DISPLAY INVISIBLE (-1475 2900);
FORCEPROP 1 LAST PATH I334
J 0
(-1525 3050);
DISPLAY 0.978723 (-1525 3050);
PAINT WHITE (-1525 3050);
DISPLAY INVISIBLE (-1525 3050);
FORCEPROP 1 LAST WATTAGE 1/16W
J 2
(-1075 2825);
DISPLAY 0.489362 (-1075 2825);
PAINT SKYBLUE (-1075 2825);
DISPLAY INVISIBLE (-1075 2825);
FORCEPROP 1 LAST MATERIAL CHIP
J 0
(-1050 2825);
DISPLAY 0.489362 (-1050 2825);
PAINT SKYBLUE (-1050 2825);
DISPLAY INVISIBLE (-1050 2825);
FORCEPROP 1 LAST TOLERANCE 5%
J 0
(-1500 2825);
DISPLAY 0.489362 (-1500 2825);
PAINT SKYBLUE (-1500 2825);
DISPLAY INVISIBLE (-1500 2825);
FORCEPROP 1 LAST PART_NUMBER CS00002JB38
J 0
(-1450 2950);
DISPLAY 0.489362 (-1450 2950);
PAINT SKYBLUE (-1450 2950);
DISPLAY INVISIBLE (-1450 2950);
FORCEPROP 1 LAST PACK_TYPE 0402LF
J 0
(-1425 2825);
DISPLAY 0.489362 (-1425 2825);
PAINT SKYBLUE (-1425 2825);
DISPLAY INVISIBLE (-1425 2825);
FORCEADD Q_RES..1
(-1475 2950);
FORCEPROP 1 LAST LOCATION R481
J 0
(-1375 2950);
DISPLAY 0.489362 (-1375 2950);
PAINT SKYBLUE (-1375 2950);
FORCEPROP 0 LAST $SEC 1
J 0
(-1375 3000);
DISPLAY 0.680851 (-1375 3000);
PAINT MONO (-1375 3000);
DISPLAY INVISIBLE (-1375 3000);
FORCEPROP 0 LAST CDS_SEC 1
J 0
(-1375 3000);
DISPLAY 0.680851 (-1375 3000);
DISPLAY INVISIBLE (-1375 3000);
FORCEPROP 1 LASTPIN (-1575 2950) $PN 1
J 0
(-1563 2962);
DISPLAY 0.489362 (-1563 2962);
PAINT MONO (-1563 2962);
FORCEPROP 1 LASTPIN (-1375 2950) $PN 2
J 0
(-1413 2962);
DISPLAY 0.489362 (-1413 2962);
PAINT MONO (-1413 2962);
FORCEPROP 1 LAST VALUE 0
J 2
(-1575 2950);
DISPLAY 0.489362 (-1575 2950);
PAINT SKYBLUE (-1575 2950);
FORCEPROP 2 LAST CDS_LIB pure_quanta
J 0
(-1475 2950);
DISPLAY INVISIBLE (-1475 2950);
FORCEPROP 1 LAST PATH I335
J 0
(-1525 3100);
DISPLAY 0.978723 (-1525 3100);
PAINT WHITE (-1525 3100);
DISPLAY INVISIBLE (-1525 3100);
FORCEPROP 1 LAST WATTAGE 1/16W
J 2
(-1075 2875);
DISPLAY 0.489362 (-1075 2875);
PAINT SKYBLUE (-1075 2875);
DISPLAY INVISIBLE (-1075 2875);
FORCEPROP 1 LAST MATERIAL CHIP
J 0
(-1050 2875);
DISPLAY 0.489362 (-1050 2875);
PAINT SKYBLUE (-1050 2875);
DISPLAY INVISIBLE (-1050 2875);
FORCEPROP 1 LAST TOLERANCE 5%
J 0
(-1500 2875);
DISPLAY 0.489362 (-1500 2875);
PAINT SKYBLUE (-1500 2875);
DISPLAY INVISIBLE (-1500 2875);
FORCEPROP 1 LAST PART_NUMBER CS00002JB38
J 0
(-1450 3000);
DISPLAY 0.489362 (-1450 3000);
PAINT SKYBLUE (-1450 3000);
DISPLAY INVISIBLE (-1450 3000);
FORCEPROP 1 LAST PACK_TYPE 0402LF
J 0
(-1425 2875);
DISPLAY 0.489362 (-1425 2875);
PAINT SKYBLUE (-1425 2875);
DISPLAY INVISIBLE (-1425 2875);
FORCEADD Q_RES..1
(-1475 2850);
FORCEPROP 1 LAST LOCATION R484
J 0
(-1375 2850);
DISPLAY 0.489362 (-1375 2850);
PAINT SKYBLUE (-1375 2850);
FORCEPROP 0 LAST $SEC 1
J 0
(-1375 2900);
DISPLAY 0.680851 (-1375 2900);
PAINT MONO (-1375 2900);
DISPLAY INVISIBLE (-1375 2900);
FORCEPROP 0 LAST CDS_SEC 1
J 0
(-1375 2900);
DISPLAY 0.680851 (-1375 2900);
DISPLAY INVISIBLE (-1375 2900);
FORCEPROP 1 LASTPIN (-1575 2850) $PN 1
J 0
(-1563 2862);
DISPLAY 0.489362 (-1563 2862);
PAINT MONO (-1563 2862);
FORCEPROP 1 LASTPIN (-1375 2850) $PN 2
J 0
(-1413 2862);
DISPLAY 0.489362 (-1413 2862);
PAINT MONO (-1413 2862);
FORCEPROP 1 LAST VALUE 0
J 2
(-1575 2850);
DISPLAY 0.489362 (-1575 2850);
PAINT SKYBLUE (-1575 2850);
FORCEPROP 2 LAST CDS_LIB pure_quanta
J 0
(-1475 2850);
DISPLAY INVISIBLE (-1475 2850);
FORCEPROP 1 LAST PATH I336
J 0
(-1525 3000);
DISPLAY 0.978723 (-1525 3000);
PAINT WHITE (-1525 3000);
DISPLAY INVISIBLE (-1525 3000);
FORCEPROP 1 LAST WATTAGE 1/16W
J 2
(-1075 2775);
DISPLAY 0.489362 (-1075 2775);
PAINT SKYBLUE (-1075 2775);
DISPLAY INVISIBLE (-1075 2775);
FORCEPROP 1 LAST MATERIAL CHIP
J 0
(-1050 2775);
DISPLAY 0.489362 (-1050 2775);
PAINT SKYBLUE (-1050 2775);
DISPLAY INVISIBLE (-1050 2775);
FORCEPROP 1 LAST TOLERANCE 5%
J 0
(-1500 2775);
DISPLAY 0.489362 (-1500 2775);
PAINT SKYBLUE (-1500 2775);
DISPLAY INVISIBLE (-1500 2775);
FORCEPROP 1 LAST PART_NUMBER CS00002JB38
J 0
(-1450 2900);
DISPLAY 0.489362 (-1450 2900);
PAINT SKYBLUE (-1450 2900);
DISPLAY INVISIBLE (-1450 2900);
FORCEPROP 1 LAST PACK_TYPE 0402LF
J 0
(-1425 2775);
DISPLAY 0.489362 (-1425 2775);
PAINT SKYBLUE (-1425 2775);
DISPLAY INVISIBLE (-1425 2775);
FORCEADD Q_RES..1
(-1475 2800);
FORCEPROP 1 LAST LOCATION R485
J 0
(-1375 2800);
DISPLAY 0.489362 (-1375 2800);
PAINT SKYBLUE (-1375 2800);
FORCEPROP 0 LAST $SEC 1
J 0
(-1375 2850);
DISPLAY 0.680851 (-1375 2850);
PAINT MONO (-1375 2850);
DISPLAY INVISIBLE (-1375 2850);
FORCEPROP 0 LAST CDS_SEC 1
J 0
(-1375 2850);
DISPLAY 0.680851 (-1375 2850);
DISPLAY INVISIBLE (-1375 2850);
FORCEPROP 1 LASTPIN (-1575 2800) $PN 1
J 0
(-1563 2812);
DISPLAY 0.489362 (-1563 2812);
PAINT MONO (-1563 2812);
FORCEPROP 1 LASTPIN (-1375 2800) $PN 2
J 0
(-1413 2812);
DISPLAY 0.489362 (-1413 2812);
PAINT MONO (-1413 2812);
FORCEPROP 1 LAST VALUE 0
J 2
(-1575 2800);
DISPLAY 0.489362 (-1575 2800);
PAINT SKYBLUE (-1575 2800);
FORCEPROP 2 LAST CDS_LIB pure_quanta
J 0
(-1475 2800);
DISPLAY INVISIBLE (-1475 2800);
FORCEPROP 1 LAST PATH I337
J 0
(-1525 2950);
DISPLAY 0.978723 (-1525 2950);
PAINT WHITE (-1525 2950);
DISPLAY INVISIBLE (-1525 2950);
FORCEPROP 1 LAST WATTAGE 1/16W
J 2
(-1075 2725);
DISPLAY 0.489362 (-1075 2725);
PAINT SKYBLUE (-1075 2725);
DISPLAY INVISIBLE (-1075 2725);
FORCEPROP 1 LAST MATERIAL CHIP
J 0
(-1050 2725);
DISPLAY 0.489362 (-1050 2725);
PAINT SKYBLUE (-1050 2725);
DISPLAY INVISIBLE (-1050 2725);
FORCEPROP 1 LAST TOLERANCE 5%
J 0
(-1500 2725);
DISPLAY 0.489362 (-1500 2725);
PAINT SKYBLUE (-1500 2725);
DISPLAY INVISIBLE (-1500 2725);
FORCEPROP 1 LAST PART_NUMBER CS00002JB38
J 0
(-1450 2850);
DISPLAY 0.489362 (-1450 2850);
PAINT SKYBLUE (-1450 2850);
DISPLAY INVISIBLE (-1450 2850);
FORCEPROP 1 LAST PACK_TYPE 0402LF
J 0
(-1425 2725);
DISPLAY 0.489362 (-1425 2725);
PAINT SKYBLUE (-1425 2725);
DISPLAY INVISIBLE (-1425 2725);
FORCEADD OFFPAGE..2
R 2
(-2100 2800);
FORCEPROP 2 LAST $XR2 149 
J 0
(-2564 2800);
DISPLAY 0.638298 (-2564 2800);
PAINT MONO (-2564 2800);
FORCEPROP 2 LAST $XR1 81 
J 0
(-2444 2800);
DISPLAY 0.638298 (-2444 2800);
PAINT MONO (-2444 2800);
FORCEPROP 2 LAST $XR0 27 
J 0
(-2354 2800);
DISPLAY 0.638298 (-2354 2800);
PAINT MONO (-2354 2800);
FORCEPROP 2 LAST CDS_LIB standard
J 0
(-2100 2800);
DISPLAY INVISIBLE (-2100 2800);
FORCEPROP 1 LAST OFFPAGE TRUE
J 2
(-2425 2675);
DISPLAY 0.872340 (-2425 2675);
PAINT GREEN (-2425 2675);
DISPLAY INVISIBLE (-2425 2675);
FORCEPROP 1 LAST COMMENT_BODY TRUE
J 2
(-2055 2705);
DISPLAY 0.872340 (-2055 2705);
PAINT PEACH (-2055 2705);
DISPLAY INVISIBLE (-2055 2705);
FORCEPROP 2 LAST PATH I338
J 0
(-2350 2850);
DISPLAY 0.680851 (-2350 2850);
DISPLAY INVISIBLE (-2350 2850);
FORCEADD OFFPAGE..2
R 2
(-2100 2850);
FORCEPROP 2 LAST $XR2 149 
J 0
(-2564 2850);
DISPLAY 0.638298 (-2564 2850);
PAINT MONO (-2564 2850);
FORCEPROP 2 LAST $XR1 81 
J 0
(-2444 2850);
DISPLAY 0.638298 (-2444 2850);
PAINT MONO (-2444 2850);
FORCEPROP 2 LAST $XR0 27 
J 0
(-2354 2850);
DISPLAY 0.638298 (-2354 2850);
PAINT MONO (-2354 2850);
FORCEPROP 2 LAST CDS_LIB standard
J 0
(-2100 2850);
DISPLAY INVISIBLE (-2100 2850);
FORCEPROP 1 LAST OFFPAGE TRUE
J 2
(-2425 2725);
DISPLAY 0.872340 (-2425 2725);
PAINT GREEN (-2425 2725);
DISPLAY INVISIBLE (-2425 2725);
FORCEPROP 1 LAST COMMENT_BODY TRUE
J 2
(-2055 2755);
DISPLAY 0.872340 (-2055 2755);
PAINT PEACH (-2055 2755);
DISPLAY INVISIBLE (-2055 2755);
FORCEPROP 2 LAST PATH I339
J 0
(-2350 2900);
DISPLAY 0.680851 (-2350 2900);
DISPLAY INVISIBLE (-2350 2900);
FORCEADD OFFPAGE..2
R 2
(-2100 2900);
FORCEPROP 2 LAST $XR2 149 
J 0
(-2564 2900);
DISPLAY 0.638298 (-2564 2900);
PAINT MONO (-2564 2900);
FORCEPROP 2 LAST $XR1 81 
J 0
(-2444 2900);
DISPLAY 0.638298 (-2444 2900);
PAINT MONO (-2444 2900);
FORCEPROP 2 LAST $XR0 27 
J 0
(-2354 2900);
DISPLAY 0.638298 (-2354 2900);
PAINT MONO (-2354 2900);
FORCEPROP 2 LAST CDS_LIB standard
J 0
(-2100 2900);
DISPLAY INVISIBLE (-2100 2900);
FORCEPROP 1 LAST OFFPAGE TRUE
J 2
(-2425 2775);
DISPLAY 0.872340 (-2425 2775);
PAINT GREEN (-2425 2775);
DISPLAY INVISIBLE (-2425 2775);
FORCEPROP 1 LAST COMMENT_BODY TRUE
J 2
(-2055 2805);
DISPLAY 0.872340 (-2055 2805);
PAINT PEACH (-2055 2805);
DISPLAY INVISIBLE (-2055 2805);
FORCEPROP 2 LAST PATH I340
J 0
(-2350 2950);
DISPLAY 0.680851 (-2350 2950);
DISPLAY INVISIBLE (-2350 2950);
FORCEADD OFFPAGE..2
R 2
(-2100 2950);
FORCEPROP 2 LAST $XR1 81 
J 0
(-2444 2950);
DISPLAY 0.638298 (-2444 2950);
PAINT MONO (-2444 2950);
FORCEPROP 2 LAST $XR0 27 
J 0
(-2354 2950);
DISPLAY 0.638298 (-2354 2950);
PAINT MONO (-2354 2950);
FORCEPROP 2 LAST CDS_LIB standard
J 0
(-2100 2950);
DISPLAY INVISIBLE (-2100 2950);
FORCEPROP 1 LAST OFFPAGE TRUE
J 2
(-2425 2825);
DISPLAY 0.872340 (-2425 2825);
PAINT GREEN (-2425 2825);
DISPLAY INVISIBLE (-2425 2825);
FORCEPROP 1 LAST COMMENT_BODY TRUE
J 2
(-2055 2855);
DISPLAY 0.872340 (-2055 2855);
PAINT PEACH (-2055 2855);
DISPLAY INVISIBLE (-2055 2855);
FORCEPROP 2 LAST PATH I341
J 0
(-2350 3000);
DISPLAY 0.680851 (-2350 3000);
DISPLAY INVISIBLE (-2350 3000);
FORCEADD OFFPAGE..3
(-1975 4425);
FORCEPROP 2 LAST $XR2 149 
J 0
(-1581 4425);
DISPLAY 0.638298 (-1581 4425);
PAINT MONO (-1581 4425);
FORCEPROP 2 LAST $XR1 81 
J 0
(-1671 4425);
DISPLAY 0.638298 (-1671 4425);
PAINT MONO (-1671 4425);
FORCEPROP 2 LAST $XR0 27 
J 0
(-1761 4425);
DISPLAY 0.638298 (-1761 4425);
PAINT MONO (-1761 4425);
FORCEPROP 2 LAST CDS_LIB standard
J 0
(-1975 4425);
DISPLAY INVISIBLE (-1975 4425);
FORCEPROP 1 LAST OFFPAGE TRUE
J 0
(-1650 4300);
DISPLAY 0.872340 (-1650 4300);
PAINT GREEN (-1650 4300);
DISPLAY INVISIBLE (-1650 4300);
FORCEPROP 1 LAST COMMENT_BODY TRUE
J 0
(-2025 4325);
DISPLAY 0.872340 (-2025 4325);
PAINT GREEN (-2025 4325);
DISPLAY INVISIBLE (-2025 4325);
FORCEPROP 2 LAST PATH I342
J 0
(-1575 4475);
DISPLAY 0.680851 (-1575 4475);
DISPLAY INVISIBLE (-1575 4475);
FORCEADD OFFPAGE..3
(-1975 4575);
FORCEPROP 2 LAST $XR1 81 
J 0
(-1671 4575);
DISPLAY 0.638298 (-1671 4575);
PAINT MONO (-1671 4575);
FORCEPROP 2 LAST $XR0 27 
J 0
(-1761 4575);
DISPLAY 0.638298 (-1761 4575);
PAINT MONO (-1761 4575);
FORCEPROP 2 LAST CDS_LIB standard
J 0
(-1975 4575);
DISPLAY INVISIBLE (-1975 4575);
FORCEPROP 1 LAST OFFPAGE TRUE
J 0
(-1650 4450);
DISPLAY 0.872340 (-1650 4450);
PAINT GREEN (-1650 4450);
DISPLAY INVISIBLE (-1650 4450);
FORCEPROP 1 LAST COMMENT_BODY TRUE
J 0
(-2025 4475);
DISPLAY 0.872340 (-2025 4475);
PAINT GREEN (-2025 4475);
DISPLAY INVISIBLE (-2025 4475);
FORCEPROP 2 LAST PATH I343
J 0
(-1650 4625);
DISPLAY 0.680851 (-1650 4625);
DISPLAY INVISIBLE (-1650 4625);
FORCEADD OFFPAGE..3
(-1975 4525);
FORCEPROP 2 LAST $XR2 149 
J 0
(-1581 4525);
DISPLAY 0.638298 (-1581 4525);
PAINT MONO (-1581 4525);
FORCEPROP 2 LAST $XR1 81 
J 0
(-1671 4525);
DISPLAY 0.638298 (-1671 4525);
PAINT MONO (-1671 4525);
FORCEPROP 2 LAST $XR0 27 
J 0
(-1761 4525);
DISPLAY 0.638298 (-1761 4525);
PAINT MONO (-1761 4525);
FORCEPROP 2 LAST CDS_LIB standard
J 0
(-1975 4525);
DISPLAY INVISIBLE (-1975 4525);
FORCEPROP 1 LAST OFFPAGE TRUE
J 0
(-1650 4400);
DISPLAY 0.872340 (-1650 4400);
PAINT GREEN (-1650 4400);
DISPLAY INVISIBLE (-1650 4400);
FORCEPROP 1 LAST COMMENT_BODY TRUE
J 0
(-2025 4425);
DISPLAY 0.872340 (-2025 4425);
PAINT GREEN (-2025 4425);
DISPLAY INVISIBLE (-2025 4425);
FORCEPROP 2 LAST PATH I344
J 0
(-1575 4575);
DISPLAY 0.680851 (-1575 4575);
DISPLAY INVISIBLE (-1575 4575);
FORCEADD OFFPAGE..3
(-1975 4475);
FORCEPROP 2 LAST $XR2 149 
J 0
(-1581 4475);
DISPLAY 0.638298 (-1581 4475);
PAINT MONO (-1581 4475);
FORCEPROP 2 LAST $XR1 81 
J 0
(-1671 4475);
DISPLAY 0.638298 (-1671 4475);
PAINT MONO (-1671 4475);
FORCEPROP 2 LAST $XR0 27 
J 0
(-1761 4475);
DISPLAY 0.638298 (-1761 4475);
PAINT MONO (-1761 4475);
FORCEPROP 2 LAST CDS_LIB standard
J 0
(-1975 4475);
DISPLAY INVISIBLE (-1975 4475);
FORCEPROP 1 LAST OFFPAGE TRUE
J 0
(-1650 4350);
DISPLAY 0.872340 (-1650 4350);
PAINT GREEN (-1650 4350);
DISPLAY INVISIBLE (-1650 4350);
FORCEPROP 1 LAST COMMENT_BODY TRUE
J 0
(-2025 4375);
DISPLAY 0.872340 (-2025 4375);
PAINT GREEN (-2025 4375);
DISPLAY INVISIBLE (-2025 4375);
FORCEPROP 2 LAST PATH I345
J 0
(-1575 4525);
DISPLAY 0.680851 (-1575 4525);
DISPLAY INVISIBLE (-1575 4525);
FORCEADD Q_RES..1
(-2725 4575);
FORCEPROP 1 LAST LOCATION R156
J 0
(-2625 4575);
DISPLAY 0.489362 (-2625 4575);
PAINT SKYBLUE (-2625 4575);
FORCEPROP 0 LAST $SEC 1
J 0
(-2625 4625);
DISPLAY 0.680851 (-2625 4625);
PAINT MONO (-2625 4625);
DISPLAY INVISIBLE (-2625 4625);
FORCEPROP 0 LAST CDS_SEC 1
J 0
(-2625 4625);
DISPLAY 0.680851 (-2625 4625);
DISPLAY INVISIBLE (-2625 4625);
FORCEPROP 1 LASTPIN (-2825 4575) $PN 1
J 0
(-2813 4587);
DISPLAY 0.489362 (-2813 4587);
PAINT MONO (-2813 4587);
FORCEPROP 1 LASTPIN (-2625 4575) $PN 2
J 0
(-2663 4587);
DISPLAY 0.489362 (-2663 4587);
PAINT MONO (-2663 4587);
FORCEPROP 1 LAST VALUE 0
J 2
(-2825 4575);
DISPLAY 0.489362 (-2825 4575);
PAINT SKYBLUE (-2825 4575);
FORCEPROP 2 LAST CDS_LIB pure_quanta
J 0
(-2725 4575);
DISPLAY INVISIBLE (-2725 4575);
FORCEPROP 1 LAST PATH I346
J 0
(-2775 4725);
DISPLAY 0.978723 (-2775 4725);
PAINT WHITE (-2775 4725);
DISPLAY INVISIBLE (-2775 4725);
FORCEPROP 1 LAST WATTAGE 1/16W
J 2
(-2325 4500);
DISPLAY 0.489362 (-2325 4500);
PAINT SKYBLUE (-2325 4500);
DISPLAY INVISIBLE (-2325 4500);
FORCEPROP 1 LAST MATERIAL CHIP
J 0
(-2300 4500);
DISPLAY 0.489362 (-2300 4500);
PAINT SKYBLUE (-2300 4500);
DISPLAY INVISIBLE (-2300 4500);
FORCEPROP 1 LAST TOLERANCE 5%
J 0
(-2750 4500);
DISPLAY 0.489362 (-2750 4500);
PAINT SKYBLUE (-2750 4500);
DISPLAY INVISIBLE (-2750 4500);
FORCEPROP 1 LAST PART_NUMBER CS00002JB38
J 0
(-2700 4625);
DISPLAY 0.489362 (-2700 4625);
PAINT SKYBLUE (-2700 4625);
DISPLAY INVISIBLE (-2700 4625);
FORCEPROP 1 LAST PACK_TYPE 0402LF
J 0
(-2675 4500);
DISPLAY 0.489362 (-2675 4500);
PAINT SKYBLUE (-2675 4500);
DISPLAY INVISIBLE (-2675 4500);
FORCEADD Q_RES..1
(-2725 4525);
FORCEPROP 1 LAST LOCATION R157
J 0
(-2625 4525);
DISPLAY 0.489362 (-2625 4525);
PAINT SKYBLUE (-2625 4525);
FORCEPROP 0 LAST $SEC 1
J 0
(-2625 4575);
DISPLAY 0.680851 (-2625 4575);
PAINT MONO (-2625 4575);
DISPLAY INVISIBLE (-2625 4575);
FORCEPROP 0 LAST CDS_SEC 1
J 0
(-2625 4575);
DISPLAY 0.680851 (-2625 4575);
DISPLAY INVISIBLE (-2625 4575);
FORCEPROP 1 LASTPIN (-2825 4525) $PN 1
J 0
(-2813 4537);
DISPLAY 0.489362 (-2813 4537);
PAINT MONO (-2813 4537);
FORCEPROP 1 LASTPIN (-2625 4525) $PN 2
J 0
(-2663 4537);
DISPLAY 0.489362 (-2663 4537);
PAINT MONO (-2663 4537);
FORCEPROP 1 LAST VALUE 0
J 2
(-2825 4525);
DISPLAY 0.489362 (-2825 4525);
PAINT SKYBLUE (-2825 4525);
FORCEPROP 2 LAST CDS_LIB pure_quanta
J 0
(-2725 4525);
DISPLAY INVISIBLE (-2725 4525);
FORCEPROP 1 LAST PATH I347
J 0
(-2775 4675);
DISPLAY 0.978723 (-2775 4675);
PAINT WHITE (-2775 4675);
DISPLAY INVISIBLE (-2775 4675);
FORCEPROP 1 LAST WATTAGE 1/16W
J 2
(-2325 4450);
DISPLAY 0.489362 (-2325 4450);
PAINT SKYBLUE (-2325 4450);
DISPLAY INVISIBLE (-2325 4450);
FORCEPROP 1 LAST MATERIAL CHIP
J 0
(-2300 4450);
DISPLAY 0.489362 (-2300 4450);
PAINT SKYBLUE (-2300 4450);
DISPLAY INVISIBLE (-2300 4450);
FORCEPROP 1 LAST TOLERANCE 5%
J 0
(-2750 4450);
DISPLAY 0.489362 (-2750 4450);
PAINT SKYBLUE (-2750 4450);
DISPLAY INVISIBLE (-2750 4450);
FORCEPROP 1 LAST PART_NUMBER CS00002JB38
J 0
(-2700 4575);
DISPLAY 0.489362 (-2700 4575);
PAINT SKYBLUE (-2700 4575);
DISPLAY INVISIBLE (-2700 4575);
FORCEPROP 1 LAST PACK_TYPE 0402LF
J 0
(-2675 4450);
DISPLAY 0.489362 (-2675 4450);
PAINT SKYBLUE (-2675 4450);
DISPLAY INVISIBLE (-2675 4450);
FORCEADD Q_RES..1
(-2725 4425);
FORCEPROP 1 LAST LOCATION R357
J 0
(-2625 4425);
DISPLAY 0.489362 (-2625 4425);
PAINT SKYBLUE (-2625 4425);
FORCEPROP 0 LAST $SEC 1
J 0
(-2625 4475);
DISPLAY 0.680851 (-2625 4475);
PAINT MONO (-2625 4475);
DISPLAY INVISIBLE (-2625 4475);
FORCEPROP 0 LAST CDS_SEC 1
J 0
(-2625 4475);
DISPLAY 0.680851 (-2625 4475);
DISPLAY INVISIBLE (-2625 4475);
FORCEPROP 1 LASTPIN (-2825 4425) $PN 1
J 0
(-2813 4437);
DISPLAY 0.489362 (-2813 4437);
PAINT MONO (-2813 4437);
FORCEPROP 1 LASTPIN (-2625 4425) $PN 2
J 0
(-2663 4437);
DISPLAY 0.489362 (-2663 4437);
PAINT MONO (-2663 4437);
FORCEPROP 1 LAST VALUE 0
J 2
(-2825 4425);
DISPLAY 0.489362 (-2825 4425);
PAINT SKYBLUE (-2825 4425);
FORCEPROP 2 LAST CDS_LIB pure_quanta
J 0
(-2725 4425);
DISPLAY INVISIBLE (-2725 4425);
FORCEPROP 1 LAST PATH I348
J 0
(-2775 4575);
DISPLAY 0.978723 (-2775 4575);
PAINT WHITE (-2775 4575);
DISPLAY INVISIBLE (-2775 4575);
FORCEPROP 1 LAST PACK_TYPE 0402LF
J 0
(-2675 4350);
DISPLAY 0.489362 (-2675 4350);
PAINT SKYBLUE (-2675 4350);
DISPLAY INVISIBLE (-2675 4350);
FORCEPROP 1 LAST PART_NUMBER CS00002JB38
J 0
(-2700 4475);
DISPLAY 0.489362 (-2700 4475);
PAINT SKYBLUE (-2700 4475);
DISPLAY INVISIBLE (-2700 4475);
FORCEPROP 1 LAST TOLERANCE 5%
J 0
(-2750 4350);
DISPLAY 0.489362 (-2750 4350);
PAINT SKYBLUE (-2750 4350);
DISPLAY INVISIBLE (-2750 4350);
FORCEPROP 1 LAST MATERIAL CHIP
J 0
(-2300 4350);
DISPLAY 0.489362 (-2300 4350);
PAINT SKYBLUE (-2300 4350);
DISPLAY INVISIBLE (-2300 4350);
FORCEPROP 1 LAST WATTAGE 1/16W
J 2
(-2325 4350);
DISPLAY 0.489362 (-2325 4350);
PAINT SKYBLUE (-2325 4350);
DISPLAY INVISIBLE (-2325 4350);
FORCEADD Q_RES..1
(-2725 4475);
FORCEPROP 1 LAST LOCATION R356
J 0
(-2625 4475);
DISPLAY 0.489362 (-2625 4475);
PAINT SKYBLUE (-2625 4475);
FORCEPROP 0 LAST $SEC 1
J 0
(-2625 4525);
DISPLAY 0.680851 (-2625 4525);
PAINT MONO (-2625 4525);
DISPLAY INVISIBLE (-2625 4525);
FORCEPROP 0 LAST CDS_SEC 1
J 0
(-2625 4525);
DISPLAY 0.680851 (-2625 4525);
DISPLAY INVISIBLE (-2625 4525);
FORCEPROP 1 LASTPIN (-2825 4475) $PN 1
J 0
(-2813 4487);
DISPLAY 0.489362 (-2813 4487);
PAINT MONO (-2813 4487);
FORCEPROP 1 LASTPIN (-2625 4475) $PN 2
J 0
(-2663 4487);
DISPLAY 0.489362 (-2663 4487);
PAINT MONO (-2663 4487);
FORCEPROP 1 LAST VALUE 0
J 2
(-2825 4475);
DISPLAY 0.489362 (-2825 4475);
PAINT SKYBLUE (-2825 4475);
FORCEPROP 2 LAST CDS_LIB pure_quanta
J 0
(-2725 4475);
DISPLAY INVISIBLE (-2725 4475);
FORCEPROP 1 LAST PATH I349
J 0
(-2775 4625);
DISPLAY 0.978723 (-2775 4625);
PAINT WHITE (-2775 4625);
DISPLAY INVISIBLE (-2775 4625);
FORCEPROP 1 LAST WATTAGE 1/16W
J 2
(-2325 4400);
DISPLAY 0.489362 (-2325 4400);
PAINT SKYBLUE (-2325 4400);
DISPLAY INVISIBLE (-2325 4400);
FORCEPROP 1 LAST MATERIAL CHIP
J 0
(-2300 4400);
DISPLAY 0.489362 (-2300 4400);
PAINT SKYBLUE (-2300 4400);
DISPLAY INVISIBLE (-2300 4400);
FORCEPROP 1 LAST TOLERANCE 5%
J 0
(-2750 4400);
DISPLAY 0.489362 (-2750 4400);
PAINT SKYBLUE (-2750 4400);
DISPLAY INVISIBLE (-2750 4400);
FORCEPROP 1 LAST PART_NUMBER CS00002JB38
J 0
(-2700 4525);
DISPLAY 0.489362 (-2700 4525);
PAINT SKYBLUE (-2700 4525);
DISPLAY INVISIBLE (-2700 4525);
FORCEPROP 1 LAST PACK_TYPE 0402LF
J 0
(-2675 4400);
DISPLAY 0.489362 (-2675 4400);
PAINT SKYBLUE (-2675 4400);
DISPLAY INVISIBLE (-2675 4400);
FORCEADD OFFPAGE..4
(-1575 1625);
FORCEPROP 2 LAST $XR1 80 
J 0
(-1269 1625);
DISPLAY 0.638298 (-1269 1625);
PAINT MONO (-1269 1625);
FORCEPROP 2 LAST $XR0 144 
J 0
(-1389 1625);
DISPLAY 0.638298 (-1389 1625);
PAINT MONO (-1389 1625);
FORCEPROP 2 LAST CDS_LIB standard
J 0
(-1575 1625);
DISPLAY INVISIBLE (-1575 1625);
FORCEPROP 1 LAST OFFPAGE TRUE
J 0
(-1250 1500);
DISPLAY 0.872340 (-1250 1500);
PAINT GREEN (-1250 1500);
DISPLAY INVISIBLE (-1250 1500);
FORCEPROP 1 LAST COMMENT_BODY TRUE
J 0
(-1600 1525);
DISPLAY 0.872340 (-1600 1525);
PAINT GREEN (-1600 1525);
DISPLAY INVISIBLE (-1600 1525);
FORCEPROP 2 LAST PATH I352
J 0
(-1400 1700);
DISPLAY 0.680851 (-1400 1700);
DISPLAY INVISIBLE (-1400 1700);
FORCEADD Q_RES..1
(-2500 1625);
FORCEPROP 1 LAST LOCATION R1204
J 0
(-2550 1675);
DISPLAY 0.489362 (-2550 1675);
PAINT SKYBLUE (-2550 1675);
FORCEPROP 0 LAST $SEC 1
J 0
(-2550 1725);
DISPLAY 0.680851 (-2550 1725);
PAINT MONO (-2550 1725);
DISPLAY INVISIBLE (-2550 1725);
FORCEPROP 0 LAST CDS_SEC 1
J 0
(-2550 1725);
DISPLAY 0.680851 (-2550 1725);
DISPLAY INVISIBLE (-2550 1725);
FORCEPROP 1 LASTPIN (-2600 1625) $PN 1
J 0
(-2588 1637);
DISPLAY 0.489362 (-2588 1637);
PAINT MONO (-2588 1637);
FORCEPROP 1 LASTPIN (-2400 1625) $PN 2
J 0
(-2438 1637);
DISPLAY 0.489362 (-2438 1637);
PAINT MONO (-2438 1637);
FORCEPROP 1 LAST VALUE 0
J 2
(-2600 1625);
DISPLAY 0.489362 (-2600 1625);
PAINT SKYBLUE (-2600 1625);
FORCEPROP 2 LAST CDS_LIB pure_quanta
J 0
(-2500 1625);
DISPLAY INVISIBLE (-2500 1625);
FORCEPROP 1 LAST PATH I353
J 0
(-2550 1775);
DISPLAY 0.978723 (-2550 1775);
PAINT WHITE (-2550 1775);
DISPLAY INVISIBLE (-2550 1775);
FORCEPROP 1 LAST WATTAGE 1/16W
J 2
(-2100 1550);
DISPLAY 0.489362 (-2100 1550);
PAINT SKYBLUE (-2100 1550);
DISPLAY INVISIBLE (-2100 1550);
FORCEPROP 1 LAST MATERIAL CHIP
J 0
(-2075 1550);
DISPLAY 0.489362 (-2075 1550);
PAINT SKYBLUE (-2075 1550);
DISPLAY INVISIBLE (-2075 1550);
FORCEPROP 1 LAST TOLERANCE 5%
J 0
(-2525 1550);
DISPLAY 0.489362 (-2525 1550);
PAINT SKYBLUE (-2525 1550);
DISPLAY INVISIBLE (-2525 1550);
FORCEPROP 1 LAST PART_NUMBER CS00002JB38
J 0
(-2475 1675);
DISPLAY 0.489362 (-2475 1675);
PAINT SKYBLUE (-2475 1675);
DISPLAY INVISIBLE (-2475 1675);
FORCEPROP 1 LAST PACK_TYPE 0402LF
J 0
(-2450 1550);
DISPLAY 0.489362 (-2450 1550);
PAINT SKYBLUE (-2450 1550);
DISPLAY INVISIBLE (-2450 1550);
FORCEADD TP..1
R 6
(-5975 1625);
FORCEPROP 1 LAST LOCATION TP9
J 1
(-5975 1527);
DISPLAY 0.489362 (-5975 1527);
PAINT SKYBLUE (-5975 1527);
FORCEPROP 0 LAST $SEC 1
J 0
(-6000 1600);
DISPLAY 0.680851 (-6000 1600);
PAINT MONO (-6000 1600);
DISPLAY INVISIBLE (-6000 1600);
FORCEPROP 0 LAST CDS_SEC 1
J 0
(-6000 1600);
DISPLAY 1.021277 (-6000 1600);
DISPLAY INVISIBLE (-6000 1600);
FORCEPROP 0 LASTPIN (-5975 1675) $PN 1
R 1
J 0
(-5985 1685);
DISPLAY 0.489362 (-5985 1685);
PAINT MONO (-5985 1685);
FORCEPROP 1 LAST MATERIAL NA
J 0
(-6000 1577);
DISPLAY 0.489362 (-6000 1577);
PAINT SKYBLUE (-6000 1577);
FORCEPROP 2 LAST CDS_LIB pure_quanta
J 0
(-5975 1625);
DISPLAY INVISIBLE (-5975 1625);
FORCEPROP 1 LASTPIN (-5975 1675) $PIN_NUMBER ?
J 2
(-5925 1675);
DISPLAY 0.702128 (-5925 1675);
PAINT MONO (-5925 1675);
DISPLAY INVISIBLE (-5925 1675);
FORCEPROP 1 LAST PATH I355
J 1
(-5970 1580);
DISPLAY 0.446809 (-5970 1580);
PAINT GREEN (-5970 1580);
DISPLAY INVISIBLE (-5970 1580);
FORCEPROP 1 LAST PART_NUMBER TP30
J 1
(-5920 1649);
DISPLAY 0.446809 (-5920 1649);
PAINT SKYBLUE (-5920 1649);
DISPLAY INVISIBLE (-5920 1649);
FORCEPROP 1 LAST PACK_TYPE TP
J 1
(-5920 1669);
DISPLAY 0.446809 (-5920 1669);
PAINT SKYBLUE (-5920 1669);
DISPLAY INVISIBLE (-5920 1669);
FORCEADD TP..1
R 6
(-6125 1625);
FORCEPROP 1 LAST LOCATION TP8
J 1
(-6125 1525);
DISPLAY 0.489362 (-6125 1525);
PAINT SKYBLUE (-6125 1525);
FORCEPROP 0 LAST $SEC 1
J 0
(-6150 1600);
DISPLAY 0.680851 (-6150 1600);
PAINT MONO (-6150 1600);
DISPLAY INVISIBLE (-6150 1600);
FORCEPROP 0 LAST CDS_SEC 1
J 0
(-6150 1600);
DISPLAY 1.021277 (-6150 1600);
DISPLAY INVISIBLE (-6150 1600);
FORCEPROP 0 LASTPIN (-6125 1675) $PN 1
R 1
J 0
(-6135 1685);
DISPLAY 0.489362 (-6135 1685);
PAINT MONO (-6135 1685);
FORCEPROP 1 LAST MATERIAL NA
J 0
(-6150 1577);
DISPLAY 0.489362 (-6150 1577);
PAINT SKYBLUE (-6150 1577);
FORCEPROP 1 LASTPIN (-6125 1675) $PIN_NUMBER ?
J 2
(-6075 1675);
DISPLAY 0.702128 (-6075 1675);
PAINT MONO (-6075 1675);
DISPLAY INVISIBLE (-6075 1675);
FORCEPROP 2 LAST CDS_LIB pure_quanta
J 0
(-6125 1625);
DISPLAY INVISIBLE (-6125 1625);
FORCEPROP 1 LAST PATH I356
J 1
(-6120 1580);
DISPLAY 0.446809 (-6120 1580);
PAINT GREEN (-6120 1580);
DISPLAY INVISIBLE (-6120 1580);
FORCEPROP 1 LAST PART_NUMBER TP30
J 1
(-6070 1649);
DISPLAY 0.446809 (-6070 1649);
PAINT SKYBLUE (-6070 1649);
DISPLAY INVISIBLE (-6070 1649);
FORCEPROP 1 LAST PACK_TYPE TP
J 1
(-6070 1669);
DISPLAY 0.446809 (-6070 1669);
PAINT SKYBLUE (-6070 1669);
DISPLAY INVISIBLE (-6070 1669);
FORCEADD TP..1
R 6
(-6200 1625);
FORCEPROP 1 LAST LOCATION TP7
J 1
(-6200 1525);
DISPLAY 0.489362 (-6200 1525);
PAINT SKYBLUE (-6200 1525);
FORCEPROP 0 LAST $SEC 1
J 0
(-6225 1600);
DISPLAY 0.680851 (-6225 1600);
PAINT MONO (-6225 1600);
DISPLAY INVISIBLE (-6225 1600);
FORCEPROP 0 LAST CDS_SEC 1
J 0
(-6225 1600);
DISPLAY 1.021277 (-6225 1600);
DISPLAY INVISIBLE (-6225 1600);
FORCEPROP 0 LASTPIN (-6200 1675) $PN 1
R 1
J 0
(-6210 1685);
DISPLAY 0.489362 (-6210 1685);
PAINT MONO (-6210 1685);
FORCEPROP 1 LAST MATERIAL NA
J 0
(-6225 1577);
DISPLAY 0.489362 (-6225 1577);
PAINT SKYBLUE (-6225 1577);
FORCEPROP 2 LAST CDS_LIB pure_quanta
J 0
(-6200 1625);
DISPLAY INVISIBLE (-6200 1625);
FORCEPROP 1 LASTPIN (-6200 1675) $PIN_NUMBER ?
J 2
(-6150 1675);
DISPLAY 0.702128 (-6150 1675);
PAINT MONO (-6150 1675);
DISPLAY INVISIBLE (-6150 1675);
FORCEPROP 1 LAST PATH I357
J 1
(-6195 1580);
DISPLAY 0.446809 (-6195 1580);
PAINT GREEN (-6195 1580);
DISPLAY INVISIBLE (-6195 1580);
FORCEPROP 1 LAST PART_NUMBER TP30
J 1
(-6145 1649);
DISPLAY 0.446809 (-6145 1649);
PAINT SKYBLUE (-6145 1649);
DISPLAY INVISIBLE (-6145 1649);
FORCEPROP 1 LAST PACK_TYPE TP
J 1
(-6145 1669);
DISPLAY 0.446809 (-6145 1669);
PAINT SKYBLUE (-6145 1669);
DISPLAY INVISIBLE (-6145 1669);
FORCEADD TP..1
R 6
(-6275 1625);
FORCEPROP 1 LAST LOCATION TP6
J 1
(-6275 1525);
DISPLAY 0.489362 (-6275 1525);
PAINT SKYBLUE (-6275 1525);
FORCEPROP 0 LAST $SEC 1
J 0
(-6300 1600);
DISPLAY 0.680851 (-6300 1600);
PAINT MONO (-6300 1600);
DISPLAY INVISIBLE (-6300 1600);
FORCEPROP 0 LAST CDS_SEC 1
J 0
(-6300 1600);
DISPLAY 1.021277 (-6300 1600);
DISPLAY INVISIBLE (-6300 1600);
FORCEPROP 0 LASTPIN (-6275 1675) $PN 1
R 1
J 0
(-6285 1685);
DISPLAY 0.489362 (-6285 1685);
PAINT MONO (-6285 1685);
FORCEPROP 1 LAST MATERIAL NA
J 0
(-6300 1577);
DISPLAY 0.489362 (-6300 1577);
PAINT SKYBLUE (-6300 1577);
FORCEPROP 2 LAST CDS_LIB pure_quanta
J 0
(-6275 1625);
DISPLAY INVISIBLE (-6275 1625);
FORCEPROP 1 LASTPIN (-6275 1675) $PIN_NUMBER ?
J 2
(-6225 1675);
DISPLAY 0.702128 (-6225 1675);
PAINT MONO (-6225 1675);
DISPLAY INVISIBLE (-6225 1675);
FORCEPROP 1 LAST PATH I358
J 1
(-6270 1580);
DISPLAY 0.446809 (-6270 1580);
PAINT GREEN (-6270 1580);
DISPLAY INVISIBLE (-6270 1580);
FORCEPROP 1 LAST PART_NUMBER TP30
J 1
(-6220 1649);
DISPLAY 0.446809 (-6220 1649);
PAINT SKYBLUE (-6220 1649);
DISPLAY INVISIBLE (-6220 1649);
FORCEPROP 1 LAST PACK_TYPE TP
J 1
(-6220 1669);
DISPLAY 0.446809 (-6220 1669);
PAINT SKYBLUE (-6220 1669);
DISPLAY INVISIBLE (-6220 1669);
FORCEADD TP..1
R 6
(-6350 1625);
FORCEPROP 1 LAST LOCATION TP5
J 1
(-6350 1525);
DISPLAY 0.489362 (-6350 1525);
PAINT SKYBLUE (-6350 1525);
FORCEPROP 0 LAST $SEC 1
J 0
(-6375 1600);
DISPLAY 0.680851 (-6375 1600);
PAINT MONO (-6375 1600);
DISPLAY INVISIBLE (-6375 1600);
FORCEPROP 0 LAST CDS_SEC 1
J 0
(-6375 1600);
DISPLAY 1.021277 (-6375 1600);
DISPLAY INVISIBLE (-6375 1600);
FORCEPROP 0 LASTPIN (-6350 1675) $PN 1
R 1
J 0
(-6360 1685);
DISPLAY 0.489362 (-6360 1685);
PAINT MONO (-6360 1685);
FORCEPROP 1 LAST MATERIAL NA
J 0
(-6375 1577);
DISPLAY 0.489362 (-6375 1577);
PAINT SKYBLUE (-6375 1577);
FORCEPROP 2 LAST CDS_LIB pure_quanta
J 0
(-6350 1625);
DISPLAY INVISIBLE (-6350 1625);
FORCEPROP 1 LASTPIN (-6350 1675) $PIN_NUMBER ?
J 2
(-6300 1675);
DISPLAY 0.702128 (-6300 1675);
PAINT MONO (-6300 1675);
DISPLAY INVISIBLE (-6300 1675);
FORCEPROP 1 LAST PATH I359
J 1
(-6345 1580);
DISPLAY 0.446809 (-6345 1580);
PAINT GREEN (-6345 1580);
DISPLAY INVISIBLE (-6345 1580);
FORCEPROP 1 LAST PART_NUMBER TP30
J 1
(-6295 1649);
DISPLAY 0.446809 (-6295 1649);
PAINT SKYBLUE (-6295 1649);
DISPLAY INVISIBLE (-6295 1649);
FORCEPROP 1 LAST PACK_TYPE TP
J 1
(-6295 1669);
DISPLAY 0.446809 (-6295 1669);
PAINT SKYBLUE (-6295 1669);
DISPLAY INVISIBLE (-6295 1669);
FORCEADD TP..1
R 6
(-6475 1625);
FORCEPROP 1 LAST LOCATION TP4
J 1
(-6475 1525);
DISPLAY 0.489362 (-6475 1525);
PAINT SKYBLUE (-6475 1525);
FORCEPROP 0 LAST $SEC 1
J 0
(-6500 1600);
DISPLAY 0.680851 (-6500 1600);
PAINT MONO (-6500 1600);
DISPLAY INVISIBLE (-6500 1600);
FORCEPROP 0 LAST CDS_SEC 1
J 0
(-6500 1600);
DISPLAY 1.021277 (-6500 1600);
DISPLAY INVISIBLE (-6500 1600);
FORCEPROP 0 LASTPIN (-6475 1675) $PN 1
R 1
J 0
(-6485 1685);
DISPLAY 0.489362 (-6485 1685);
PAINT MONO (-6485 1685);
FORCEPROP 1 LAST MATERIAL NA
J 0
(-6500 1577);
DISPLAY 0.489362 (-6500 1577);
PAINT SKYBLUE (-6500 1577);
FORCEPROP 2 LAST CDS_LIB pure_quanta
J 0
(-6475 1625);
DISPLAY INVISIBLE (-6475 1625);
FORCEPROP 1 LASTPIN (-6475 1675) $PIN_NUMBER ?
J 2
(-6425 1675);
DISPLAY 0.702128 (-6425 1675);
PAINT MONO (-6425 1675);
DISPLAY INVISIBLE (-6425 1675);
FORCEPROP 1 LAST PATH I360
J 1
(-6470 1580);
DISPLAY 0.446809 (-6470 1580);
PAINT GREEN (-6470 1580);
DISPLAY INVISIBLE (-6470 1580);
FORCEPROP 1 LAST PART_NUMBER TP30
J 1
(-6420 1649);
DISPLAY 0.446809 (-6420 1649);
PAINT SKYBLUE (-6420 1649);
DISPLAY INVISIBLE (-6420 1649);
FORCEPROP 1 LAST PACK_TYPE TP
J 1
(-6420 1669);
DISPLAY 0.446809 (-6420 1669);
PAINT SKYBLUE (-6420 1669);
DISPLAY INVISIBLE (-6420 1669);
FORCEADD TP..1
R 6
(-6550 1625);
FORCEPROP 1 LAST LOCATION TP3
J 1
(-6550 1525);
DISPLAY 0.489362 (-6550 1525);
PAINT SKYBLUE (-6550 1525);
FORCEPROP 0 LAST $SEC 1
J 0
(-6575 1600);
DISPLAY 0.680851 (-6575 1600);
PAINT MONO (-6575 1600);
DISPLAY INVISIBLE (-6575 1600);
FORCEPROP 0 LAST CDS_SEC 1
J 0
(-6575 1600);
DISPLAY 1.021277 (-6575 1600);
DISPLAY INVISIBLE (-6575 1600);
FORCEPROP 0 LASTPIN (-6550 1675) $PN 1
R 1
J 0
(-6560 1685);
DISPLAY 0.489362 (-6560 1685);
PAINT MONO (-6560 1685);
FORCEPROP 1 LAST MATERIAL NA
J 0
(-6575 1577);
DISPLAY 0.489362 (-6575 1577);
PAINT SKYBLUE (-6575 1577);
FORCEPROP 2 LAST CDS_LIB pure_quanta
J 0
(-6550 1625);
DISPLAY INVISIBLE (-6550 1625);
FORCEPROP 1 LASTPIN (-6550 1675) $PIN_NUMBER ?
J 2
(-6500 1675);
DISPLAY 0.702128 (-6500 1675);
PAINT MONO (-6500 1675);
DISPLAY INVISIBLE (-6500 1675);
FORCEPROP 1 LAST PATH I361
J 1
(-6545 1580);
DISPLAY 0.446809 (-6545 1580);
PAINT GREEN (-6545 1580);
DISPLAY INVISIBLE (-6545 1580);
FORCEPROP 1 LAST PART_NUMBER TP30
J 1
(-6495 1649);
DISPLAY 0.446809 (-6495 1649);
PAINT SKYBLUE (-6495 1649);
DISPLAY INVISIBLE (-6495 1649);
FORCEPROP 1 LAST PACK_TYPE TP
J 1
(-6495 1669);
DISPLAY 0.446809 (-6495 1669);
PAINT SKYBLUE (-6495 1669);
DISPLAY INVISIBLE (-6495 1669);
FORCEADD TP..1
R 6
(-6625 1625);
FORCEPROP 1 LAST LOCATION TP2
J 1
(-6625 1525);
DISPLAY 0.489362 (-6625 1525);
PAINT SKYBLUE (-6625 1525);
FORCEPROP 0 LAST $SEC 1
J 0
(-6650 1600);
DISPLAY 0.680851 (-6650 1600);
PAINT MONO (-6650 1600);
DISPLAY INVISIBLE (-6650 1600);
FORCEPROP 0 LAST CDS_SEC 1
J 0
(-6650 1600);
DISPLAY 1.021277 (-6650 1600);
DISPLAY INVISIBLE (-6650 1600);
FORCEPROP 0 LASTPIN (-6625 1675) $PN 1
R 1
J 0
(-6635 1685);
DISPLAY 0.489362 (-6635 1685);
PAINT MONO (-6635 1685);
FORCEPROP 1 LAST MATERIAL NA
J 0
(-6650 1577);
DISPLAY 0.489362 (-6650 1577);
PAINT SKYBLUE (-6650 1577);
FORCEPROP 2 LAST CDS_LIB pure_quanta
J 0
(-6625 1625);
DISPLAY INVISIBLE (-6625 1625);
FORCEPROP 1 LASTPIN (-6625 1675) $PIN_NUMBER ?
J 2
(-6575 1675);
DISPLAY 0.702128 (-6575 1675);
PAINT MONO (-6575 1675);
DISPLAY INVISIBLE (-6575 1675);
FORCEPROP 1 LAST PATH I362
J 1
(-6620 1580);
DISPLAY 0.446809 (-6620 1580);
PAINT GREEN (-6620 1580);
DISPLAY INVISIBLE (-6620 1580);
FORCEPROP 1 LAST PART_NUMBER TP30
J 1
(-6570 1649);
DISPLAY 0.446809 (-6570 1649);
PAINT SKYBLUE (-6570 1649);
DISPLAY INVISIBLE (-6570 1649);
FORCEPROP 1 LAST PACK_TYPE TP
J 1
(-6570 1669);
DISPLAY 0.446809 (-6570 1669);
PAINT SKYBLUE (-6570 1669);
DISPLAY INVISIBLE (-6570 1669);
FORCEADD UNIVERSAL_GND..1
(-150 2650);
FORCEPROP 3 LASTPIN (-150 2700) SIG_NAME GND\g
J 0
(-140 2710);
DISPLAY 0.659574 (-140 2710);
PAINT MONO (-140 2710);
DISPLAY INVISIBLE (-140 2710);
FORCEPROP 2 LAST CDS_LIB pure_quanta_power
J 0
(-150 2650);
DISPLAY INVISIBLE (-150 2650);
FORCEPROP 1 LAST PATH I364
J 0
(-75 2650);
DISPLAY 0.872340 (-75 2650);
PAINT AQUA (-75 2650);
DISPLAY INVISIBLE (-75 2650);
FORCEPROP 1 LAST HDL_POWER GND
J 1
(-125 2575);
DISPLAY 0.872340 (-125 2575);
PAINT GREEN (-125 2575);
DISPLAY INVISIBLE (-125 2575);
FORCEADD UNIVERSAL_GND..1
(-150 2025);
FORCEPROP 3 LASTPIN (-150 2075) SIG_NAME GND\g
J 0
(-140 2085);
DISPLAY 0.659574 (-140 2085);
PAINT MONO (-140 2085);
DISPLAY INVISIBLE (-140 2085);
FORCEPROP 2 LAST CDS_LIB pure_quanta_power
J 0
(-150 2025);
DISPLAY INVISIBLE (-150 2025);
FORCEPROP 1 LAST PATH I365
J 0
(-75 2025);
DISPLAY 0.872340 (-75 2025);
PAINT AQUA (-75 2025);
DISPLAY INVISIBLE (-75 2025);
FORCEPROP 1 LAST HDL_POWER GND
J 1
(-125 1950);
DISPLAY 0.872340 (-125 1950);
PAINT GREEN (-125 1950);
DISPLAY INVISIBLE (-125 1950);
FORCEADD UNIVERSAL_POWER..1
(-9050 3400);
FORCEPROP 3 LASTPIN (-9050 3350) SIG_NAME P3V3_STBY\g
J 0
(-9040 3360);
DISPLAY 0.659574 (-9040 3360);
PAINT MONO (-9040 3360);
DISPLAY INVISIBLE (-9040 3360);
FORCEPROP 1 LAST HDL_POWER P3V3_STBY
J 1
(-9050 3450);
DISPLAY 0.489362 (-9050 3450);
PAINT GREEN (-9050 3450);
FORCEPROP 2 LAST CDS_LIB pure_quanta_power
J 0
(-9050 3400);
DISPLAY INVISIBLE (-9050 3400);
FORCEPROP 1 LAST PATH I366
J 0
(-9000 3425);
DISPLAY 0.872340 (-9000 3425);
PAINT AQUA (-9000 3425);
DISPLAY INVISIBLE (-9000 3425);
FORCEADD OFFPAGE..2
(-7725 2950);
FORCEPROP 2 LAST $XR1 81 
J 0
(-7446 2950);
DISPLAY 0.638298 (-7446 2950);
PAINT MONO (-7446 2950);
FORCEPROP 2 LAST $XR0 27 
J 0
(-7536 2950);
DISPLAY 0.638298 (-7536 2950);
PAINT MONO (-7536 2950);
FORCEPROP 2 LAST CDS_LIB standard
J 0
(-7725 2950);
DISPLAY INVISIBLE (-7725 2950);
FORCEPROP 1 LAST OFFPAGE TRUE
J 0
(-7400 2825);
DISPLAY 0.872340 (-7400 2825);
PAINT GREEN (-7400 2825);
DISPLAY INVISIBLE (-7400 2825);
FORCEPROP 1 LAST COMMENT_BODY TRUE
J 0
(-7770 2855);
DISPLAY 0.872340 (-7770 2855);
PAINT PEACH (-7770 2855);
DISPLAY INVISIBLE (-7770 2855);
FORCEPROP 2 LAST PATH I374
J 0
(-7425 3000);
DISPLAY 0.680851 (-7425 3000);
DISPLAY INVISIBLE (-7425 3000);
FORCEADD OFFPAGE..2
(-7725 2900);
FORCEPROP 2 LAST $XR1 81 
J 0
(-7446 2900);
DISPLAY 0.638298 (-7446 2900);
PAINT MONO (-7446 2900);
FORCEPROP 2 LAST $XR0 27 
J 0
(-7536 2900);
DISPLAY 0.638298 (-7536 2900);
PAINT MONO (-7536 2900);
FORCEPROP 2 LAST CDS_LIB standard
J 0
(-7725 2900);
DISPLAY INVISIBLE (-7725 2900);
FORCEPROP 1 LAST OFFPAGE TRUE
J 0
(-7400 2775);
DISPLAY 0.872340 (-7400 2775);
PAINT GREEN (-7400 2775);
DISPLAY INVISIBLE (-7400 2775);
FORCEPROP 1 LAST COMMENT_BODY TRUE
J 0
(-7770 2805);
DISPLAY 0.872340 (-7770 2805);
PAINT PEACH (-7770 2805);
DISPLAY INVISIBLE (-7770 2805);
FORCEPROP 2 LAST PATH I375
J 0
(-7425 2950);
DISPLAY 0.680851 (-7425 2950);
DISPLAY INVISIBLE (-7425 2950);
FORCEADD OFFPAGE..2
(-7725 2850);
FORCEPROP 2 LAST $XR1 81 
J 0
(-7446 2850);
DISPLAY 0.638298 (-7446 2850);
PAINT MONO (-7446 2850);
FORCEPROP 2 LAST $XR0 27 
J 0
(-7536 2850);
DISPLAY 0.638298 (-7536 2850);
PAINT MONO (-7536 2850);
FORCEPROP 2 LAST CDS_LIB standard
J 0
(-7725 2850);
DISPLAY INVISIBLE (-7725 2850);
FORCEPROP 1 LAST OFFPAGE TRUE
J 0
(-7400 2725);
DISPLAY 0.872340 (-7400 2725);
PAINT GREEN (-7400 2725);
DISPLAY INVISIBLE (-7400 2725);
FORCEPROP 1 LAST COMMENT_BODY TRUE
J 0
(-7770 2755);
DISPLAY 0.872340 (-7770 2755);
PAINT PEACH (-7770 2755);
DISPLAY INVISIBLE (-7770 2755);
FORCEPROP 2 LAST PATH I376
J 0
(-7425 2900);
DISPLAY 0.680851 (-7425 2900);
DISPLAY INVISIBLE (-7425 2900);
FORCEADD Q_RES..1
(-575 5400);
FORCEPROP 1 LAST LOCATION R412
J 0
(-825 5400);
DISPLAY 0.489362 (-825 5400);
PAINT SKYBLUE (-825 5400);
FORCEPROP 0 LAST $SEC 1
J 0
(-450 5425);
DISPLAY 0.680851 (-450 5425);
PAINT MONO (-450 5425);
DISPLAY INVISIBLE (-450 5425);
FORCEPROP 0 LAST CDS_SEC 1
J 0
(-450 5425);
DISPLAY 0.680851 (-450 5425);
DISPLAY INVISIBLE (-450 5425);
FORCEPROP 1 LASTPIN (-675 5400) $PN 1
J 0
(-663 5412);
DISPLAY 0.489362 (-663 5412);
PAINT MONO (-663 5412);
FORCEPROP 1 LASTPIN (-475 5400) $PN 2
J 0
(-513 5412);
DISPLAY 0.489362 (-513 5412);
PAINT MONO (-513 5412);
FORCEPROP 1 LAST VALUE 2.2K
J 0
(-450 5400);
DISPLAY 0.489362 (-450 5400);
PAINT SKYBLUE (-450 5400);
FORCEPROP 2 LAST CDS_LIB pure_quanta
J 0
(-575 5400);
DISPLAY INVISIBLE (-575 5400);
FORCEPROP 1 LAST PATH I377
J 0
(-625 5550);
DISPLAY 0.978723 (-625 5550);
PAINT WHITE (-625 5550);
DISPLAY INVISIBLE (-625 5550);
FORCEPROP 1 LAST WATTAGE 1/16W
J 2
(-600 5250);
DISPLAY 0.978723 (-600 5250);
PAINT SKYBLUE (-600 5250);
DISPLAY INVISIBLE (-600 5250);
FORCEPROP 1 LAST MATERIAL CHIP
J 0
(-575 5250);
DISPLAY 0.978723 (-575 5250);
PAINT SKYBLUE (-575 5250);
DISPLAY INVISIBLE (-575 5250);
FORCEPROP 1 LAST TOLERANCE 5%
J 0
(-575 5300);
DISPLAY 0.978723 (-575 5300);
PAINT SKYBLUE (-575 5300);
DISPLAY INVISIBLE (-575 5300);
FORCEPROP 1 LAST PART_NUMBER CS22202JB07
J 0
(-625 5500);
DISPLAY 0.978723 (-625 5500);
PAINT SKYBLUE (-625 5500);
DISPLAY INVISIBLE (-625 5500);
FORCEPROP 1 LAST PACK_TYPE 0402LF
J 0
(-325 5250);
DISPLAY 0.978723 (-325 5250);
PAINT SKYBLUE (-325 5250);
DISPLAY INVISIBLE (-325 5250);
FORCEADD Q_RES..1
(-575 5100);
FORCEPROP 1 LAST LOCATION R418
J 0
(-825 5100);
DISPLAY 0.489362 (-825 5100);
PAINT SKYBLUE (-825 5100);
FORCEPROP 0 LAST $SEC 1
J 0
(-450 5125);
DISPLAY 0.680851 (-450 5125);
PAINT MONO (-450 5125);
DISPLAY INVISIBLE (-450 5125);
FORCEPROP 0 LAST CDS_SEC 1
J 0
(-450 5125);
DISPLAY 0.680851 (-450 5125);
DISPLAY INVISIBLE (-450 5125);
FORCEPROP 1 LASTPIN (-675 5100) $PN 1
J 0
(-663 5112);
DISPLAY 0.489362 (-663 5112);
PAINT MONO (-663 5112);
FORCEPROP 1 LASTPIN (-475 5100) $PN 2
J 0
(-513 5112);
DISPLAY 0.489362 (-513 5112);
PAINT MONO (-513 5112);
FORCEPROP 1 LAST VALUE 2.2K
J 0
(-450 5100);
DISPLAY 0.489362 (-450 5100);
PAINT SKYBLUE (-450 5100);
FORCEPROP 2 LAST CDS_LIB pure_quanta
J 0
(-575 5100);
DISPLAY INVISIBLE (-575 5100);
FORCEPROP 1 LAST PATH I378
J 0
(-625 5250);
DISPLAY 0.978723 (-625 5250);
PAINT WHITE (-625 5250);
DISPLAY INVISIBLE (-625 5250);
FORCEPROP 1 LAST WATTAGE 1/16W
J 2
(-600 4950);
DISPLAY 0.978723 (-600 4950);
PAINT SKYBLUE (-600 4950);
DISPLAY INVISIBLE (-600 4950);
FORCEPROP 1 LAST MATERIAL CHIP
J 0
(-575 4950);
DISPLAY 0.978723 (-575 4950);
PAINT SKYBLUE (-575 4950);
DISPLAY INVISIBLE (-575 4950);
FORCEPROP 1 LAST TOLERANCE 5%
J 0
(-575 5000);
DISPLAY 0.978723 (-575 5000);
PAINT SKYBLUE (-575 5000);
DISPLAY INVISIBLE (-575 5000);
FORCEPROP 1 LAST PART_NUMBER CS22202JB07
J 0
(-625 5200);
DISPLAY 0.978723 (-625 5200);
PAINT SKYBLUE (-625 5200);
DISPLAY INVISIBLE (-625 5200);
FORCEPROP 1 LAST PACK_TYPE 0402LF
J 0
(-325 4950);
DISPLAY 0.978723 (-325 4950);
PAINT SKYBLUE (-325 4950);
DISPLAY INVISIBLE (-325 4950);
FORCEADD Q_RES..1
(-575 5150);
FORCEPROP 1 LAST LOCATION R417
J 0
(-825 5150);
DISPLAY 0.489362 (-825 5150);
PAINT SKYBLUE (-825 5150);
FORCEPROP 0 LAST $SEC 1
J 0
(-450 5175);
DISPLAY 0.680851 (-450 5175);
PAINT MONO (-450 5175);
DISPLAY INVISIBLE (-450 5175);
FORCEPROP 0 LAST CDS_SEC 1
J 0
(-450 5175);
DISPLAY 0.680851 (-450 5175);
DISPLAY INVISIBLE (-450 5175);
FORCEPROP 1 LASTPIN (-675 5150) $PN 1
J 0
(-663 5162);
DISPLAY 0.489362 (-663 5162);
PAINT MONO (-663 5162);
FORCEPROP 1 LASTPIN (-475 5150) $PN 2
J 0
(-513 5162);
DISPLAY 0.489362 (-513 5162);
PAINT MONO (-513 5162);
FORCEPROP 1 LAST VALUE 2.2K
J 0
(-450 5150);
DISPLAY 0.489362 (-450 5150);
PAINT SKYBLUE (-450 5150);
FORCEPROP 2 LAST CDS_LIB pure_quanta
J 0
(-575 5150);
DISPLAY INVISIBLE (-575 5150);
FORCEPROP 1 LAST PATH I379
J 0
(-625 5300);
DISPLAY 0.978723 (-625 5300);
PAINT WHITE (-625 5300);
DISPLAY INVISIBLE (-625 5300);
FORCEPROP 1 LAST WATTAGE 1/16W
J 2
(-600 5000);
DISPLAY 0.978723 (-600 5000);
PAINT SKYBLUE (-600 5000);
DISPLAY INVISIBLE (-600 5000);
FORCEPROP 1 LAST MATERIAL CHIP
J 0
(-575 5000);
DISPLAY 0.978723 (-575 5000);
PAINT SKYBLUE (-575 5000);
DISPLAY INVISIBLE (-575 5000);
FORCEPROP 1 LAST TOLERANCE 5%
J 0
(-575 5050);
DISPLAY 0.978723 (-575 5050);
PAINT SKYBLUE (-575 5050);
DISPLAY INVISIBLE (-575 5050);
FORCEPROP 1 LAST PART_NUMBER CS22202JB07
J 0
(-625 5250);
DISPLAY 0.978723 (-625 5250);
PAINT SKYBLUE (-625 5250);
DISPLAY INVISIBLE (-625 5250);
FORCEPROP 1 LAST PACK_TYPE 0402LF
J 0
(-325 5000);
DISPLAY 0.978723 (-325 5000);
PAINT SKYBLUE (-325 5000);
DISPLAY INVISIBLE (-325 5000);
FORCEADD Q_RES..1
(-575 5600);
FORCEPROP 1 LAST LOCATION R408
J 0
(-825 5600);
DISPLAY 0.489362 (-825 5600);
PAINT SKYBLUE (-825 5600);
FORCEPROP 0 LAST $SEC 1
J 0
(-450 5625);
DISPLAY 0.680851 (-450 5625);
PAINT MONO (-450 5625);
DISPLAY INVISIBLE (-450 5625);
FORCEPROP 0 LAST CDS_SEC 1
J 0
(-450 5625);
DISPLAY 0.680851 (-450 5625);
DISPLAY INVISIBLE (-450 5625);
FORCEPROP 1 LASTPIN (-675 5600) $PN 1
J 0
(-663 5612);
DISPLAY 0.489362 (-663 5612);
PAINT MONO (-663 5612);
FORCEPROP 1 LASTPIN (-475 5600) $PN 2
J 0
(-513 5612);
DISPLAY 0.489362 (-513 5612);
PAINT MONO (-513 5612);
FORCEPROP 1 LAST VALUE 2.2K
J 0
(-450 5600);
DISPLAY 0.489362 (-450 5600);
PAINT SKYBLUE (-450 5600);
FORCEPROP 2 LAST CDS_LIB pure_quanta
J 0
(-575 5600);
DISPLAY INVISIBLE (-575 5600);
FORCEPROP 1 LAST PATH I380
J 0
(-625 5750);
DISPLAY 0.978723 (-625 5750);
PAINT WHITE (-625 5750);
DISPLAY INVISIBLE (-625 5750);
FORCEPROP 1 LAST WATTAGE 1/16W
J 2
(-600 5450);
DISPLAY 0.978723 (-600 5450);
PAINT SKYBLUE (-600 5450);
DISPLAY INVISIBLE (-600 5450);
FORCEPROP 1 LAST MATERIAL CHIP
J 0
(-575 5450);
DISPLAY 0.978723 (-575 5450);
PAINT SKYBLUE (-575 5450);
DISPLAY INVISIBLE (-575 5450);
FORCEPROP 1 LAST TOLERANCE 5%
J 0
(-575 5500);
DISPLAY 0.978723 (-575 5500);
PAINT SKYBLUE (-575 5500);
DISPLAY INVISIBLE (-575 5500);
FORCEPROP 1 LAST PART_NUMBER CS22202JB07
J 0
(-625 5700);
DISPLAY 0.978723 (-625 5700);
PAINT SKYBLUE (-625 5700);
DISPLAY INVISIBLE (-625 5700);
FORCEPROP 1 LAST PACK_TYPE 0402LF
J 0
(-325 5450);
DISPLAY 0.978723 (-325 5450);
PAINT SKYBLUE (-325 5450);
DISPLAY INVISIBLE (-325 5450);
FORCEADD Q_RES..1
(-575 5550);
FORCEPROP 1 LAST LOCATION R409
J 0
(-825 5550);
DISPLAY 0.489362 (-825 5550);
PAINT SKYBLUE (-825 5550);
FORCEPROP 0 LAST $SEC 1
J 0
(-450 5575);
DISPLAY 0.680851 (-450 5575);
PAINT MONO (-450 5575);
DISPLAY INVISIBLE (-450 5575);
FORCEPROP 0 LAST CDS_SEC 1
J 0
(-450 5575);
DISPLAY 0.680851 (-450 5575);
DISPLAY INVISIBLE (-450 5575);
FORCEPROP 1 LASTPIN (-675 5550) $PN 1
J 0
(-663 5562);
DISPLAY 0.489362 (-663 5562);
PAINT MONO (-663 5562);
FORCEPROP 1 LASTPIN (-475 5550) $PN 2
J 0
(-513 5562);
DISPLAY 0.489362 (-513 5562);
PAINT MONO (-513 5562);
FORCEPROP 1 LAST VALUE 2.2K
J 0
(-450 5550);
DISPLAY 0.489362 (-450 5550);
PAINT SKYBLUE (-450 5550);
FORCEPROP 2 LAST CDS_LIB pure_quanta
J 0
(-575 5550);
DISPLAY INVISIBLE (-575 5550);
FORCEPROP 1 LAST PATH I381
J 0
(-625 5700);
DISPLAY 0.978723 (-625 5700);
PAINT WHITE (-625 5700);
DISPLAY INVISIBLE (-625 5700);
FORCEPROP 1 LAST WATTAGE 1/16W
J 2
(-600 5400);
DISPLAY 0.978723 (-600 5400);
PAINT SKYBLUE (-600 5400);
DISPLAY INVISIBLE (-600 5400);
FORCEPROP 1 LAST MATERIAL CHIP
J 0
(-575 5400);
DISPLAY 0.978723 (-575 5400);
PAINT SKYBLUE (-575 5400);
DISPLAY INVISIBLE (-575 5400);
FORCEPROP 1 LAST TOLERANCE 5%
J 0
(-575 5450);
DISPLAY 0.978723 (-575 5450);
PAINT SKYBLUE (-575 5450);
DISPLAY INVISIBLE (-575 5450);
FORCEPROP 1 LAST PART_NUMBER CS22202JB07
J 0
(-625 5650);
DISPLAY 0.978723 (-625 5650);
PAINT SKYBLUE (-625 5650);
DISPLAY INVISIBLE (-625 5650);
FORCEPROP 1 LAST PACK_TYPE 0402LF
J 0
(-325 5400);
DISPLAY 0.978723 (-325 5400);
PAINT SKYBLUE (-325 5400);
DISPLAY INVISIBLE (-325 5400);
FORCEADD Q_RES..1
(-575 5500);
FORCEPROP 1 LAST LOCATION R410
J 0
(-825 5500);
DISPLAY 0.489362 (-825 5500);
PAINT SKYBLUE (-825 5500);
FORCEPROP 0 LAST $SEC 1
J 0
(-450 5525);
DISPLAY 0.680851 (-450 5525);
PAINT MONO (-450 5525);
DISPLAY INVISIBLE (-450 5525);
FORCEPROP 0 LAST CDS_SEC 1
J 0
(-450 5525);
DISPLAY 0.680851 (-450 5525);
DISPLAY INVISIBLE (-450 5525);
FORCEPROP 1 LASTPIN (-675 5500) $PN 1
J 0
(-663 5512);
DISPLAY 0.489362 (-663 5512);
PAINT MONO (-663 5512);
FORCEPROP 1 LASTPIN (-475 5500) $PN 2
J 0
(-513 5512);
DISPLAY 0.489362 (-513 5512);
PAINT MONO (-513 5512);
FORCEPROP 1 LAST VALUE 2.2K
J 0
(-450 5500);
DISPLAY 0.489362 (-450 5500);
PAINT SKYBLUE (-450 5500);
FORCEPROP 2 LAST CDS_LIB pure_quanta
J 0
(-575 5500);
DISPLAY INVISIBLE (-575 5500);
FORCEPROP 1 LAST PATH I382
J 0
(-625 5650);
DISPLAY 0.978723 (-625 5650);
PAINT WHITE (-625 5650);
DISPLAY INVISIBLE (-625 5650);
FORCEPROP 1 LAST WATTAGE 1/16W
J 2
(-600 5350);
DISPLAY 0.978723 (-600 5350);
PAINT SKYBLUE (-600 5350);
DISPLAY INVISIBLE (-600 5350);
FORCEPROP 1 LAST MATERIAL CHIP
J 0
(-575 5350);
DISPLAY 0.978723 (-575 5350);
PAINT SKYBLUE (-575 5350);
DISPLAY INVISIBLE (-575 5350);
FORCEPROP 1 LAST TOLERANCE 5%
J 0
(-575 5400);
DISPLAY 0.978723 (-575 5400);
PAINT SKYBLUE (-575 5400);
DISPLAY INVISIBLE (-575 5400);
FORCEPROP 1 LAST PART_NUMBER CS22202JB07
J 0
(-625 5600);
DISPLAY 0.978723 (-625 5600);
PAINT SKYBLUE (-625 5600);
DISPLAY INVISIBLE (-625 5600);
FORCEPROP 1 LAST PACK_TYPE 0402LF
J 0
(-325 5350);
DISPLAY 0.978723 (-325 5350);
PAINT SKYBLUE (-325 5350);
DISPLAY INVISIBLE (-325 5350);
FORCEADD Q_RES..1
(-575 5450);
FORCEPROP 1 LAST LOCATION R411
J 0
(-825 5450);
DISPLAY 0.489362 (-825 5450);
PAINT SKYBLUE (-825 5450);
FORCEPROP 0 LAST $SEC 1
J 0
(-450 5475);
DISPLAY 0.680851 (-450 5475);
PAINT MONO (-450 5475);
DISPLAY INVISIBLE (-450 5475);
FORCEPROP 0 LAST CDS_SEC 1
J 0
(-450 5475);
DISPLAY 0.680851 (-450 5475);
DISPLAY INVISIBLE (-450 5475);
FORCEPROP 1 LASTPIN (-675 5450) $PN 1
J 0
(-663 5462);
DISPLAY 0.489362 (-663 5462);
PAINT MONO (-663 5462);
FORCEPROP 1 LASTPIN (-475 5450) $PN 2
J 0
(-513 5462);
DISPLAY 0.489362 (-513 5462);
PAINT MONO (-513 5462);
FORCEPROP 1 LAST VALUE 2.2K
J 0
(-450 5450);
DISPLAY 0.489362 (-450 5450);
PAINT SKYBLUE (-450 5450);
FORCEPROP 2 LAST CDS_LIB pure_quanta
J 0
(-575 5450);
DISPLAY INVISIBLE (-575 5450);
FORCEPROP 1 LAST PATH I383
J 0
(-625 5600);
DISPLAY 0.978723 (-625 5600);
PAINT WHITE (-625 5600);
DISPLAY INVISIBLE (-625 5600);
FORCEPROP 1 LAST WATTAGE 1/16W
J 2
(-600 5300);
DISPLAY 0.978723 (-600 5300);
PAINT SKYBLUE (-600 5300);
DISPLAY INVISIBLE (-600 5300);
FORCEPROP 1 LAST MATERIAL CHIP
J 0
(-575 5300);
DISPLAY 0.978723 (-575 5300);
PAINT SKYBLUE (-575 5300);
DISPLAY INVISIBLE (-575 5300);
FORCEPROP 1 LAST TOLERANCE 5%
J 0
(-575 5350);
DISPLAY 0.978723 (-575 5350);
PAINT SKYBLUE (-575 5350);
DISPLAY INVISIBLE (-575 5350);
FORCEPROP 1 LAST PART_NUMBER CS22202JB07
J 0
(-625 5550);
DISPLAY 0.978723 (-625 5550);
PAINT SKYBLUE (-625 5550);
DISPLAY INVISIBLE (-625 5550);
FORCEPROP 1 LAST PACK_TYPE 0402LF
J 0
(-325 5300);
DISPLAY 0.978723 (-325 5300);
PAINT SKYBLUE (-325 5300);
DISPLAY INVISIBLE (-325 5300);
FORCEADD Q_RES..1
(-575 5350);
FORCEPROP 1 LAST LOCATION R413
J 0
(-825 5350);
DISPLAY 0.489362 (-825 5350);
PAINT SKYBLUE (-825 5350);
FORCEPROP 0 LAST $SEC 1
J 0
(-450 5375);
DISPLAY 0.680851 (-450 5375);
PAINT MONO (-450 5375);
DISPLAY INVISIBLE (-450 5375);
FORCEPROP 0 LAST CDS_SEC 1
J 0
(-450 5375);
DISPLAY 0.680851 (-450 5375);
DISPLAY INVISIBLE (-450 5375);
FORCEPROP 1 LASTPIN (-675 5350) $PN 1
J 0
(-663 5362);
DISPLAY 0.489362 (-663 5362);
PAINT MONO (-663 5362);
FORCEPROP 1 LASTPIN (-475 5350) $PN 2
J 0
(-513 5362);
DISPLAY 0.489362 (-513 5362);
PAINT MONO (-513 5362);
FORCEPROP 1 LAST VALUE 2.2K
J 0
(-450 5350);
DISPLAY 0.489362 (-450 5350);
PAINT SKYBLUE (-450 5350);
FORCEPROP 2 LAST CDS_LIB pure_quanta
J 0
(-575 5350);
DISPLAY INVISIBLE (-575 5350);
FORCEPROP 1 LAST PATH I384
J 0
(-625 5500);
DISPLAY 0.978723 (-625 5500);
PAINT WHITE (-625 5500);
DISPLAY INVISIBLE (-625 5500);
FORCEPROP 1 LAST WATTAGE 1/16W
J 2
(-600 5200);
DISPLAY 0.978723 (-600 5200);
PAINT SKYBLUE (-600 5200);
DISPLAY INVISIBLE (-600 5200);
FORCEPROP 1 LAST MATERIAL CHIP
J 0
(-575 5200);
DISPLAY 0.978723 (-575 5200);
PAINT SKYBLUE (-575 5200);
DISPLAY INVISIBLE (-575 5200);
FORCEPROP 1 LAST TOLERANCE 5%
J 0
(-575 5250);
DISPLAY 0.978723 (-575 5250);
PAINT SKYBLUE (-575 5250);
DISPLAY INVISIBLE (-575 5250);
FORCEPROP 1 LAST PART_NUMBER CS22202JB07
J 0
(-625 5450);
DISPLAY 0.978723 (-625 5450);
PAINT SKYBLUE (-625 5450);
DISPLAY INVISIBLE (-625 5450);
FORCEPROP 1 LAST PACK_TYPE 0402LF
J 0
(-325 5200);
DISPLAY 0.978723 (-325 5200);
PAINT SKYBLUE (-325 5200);
DISPLAY INVISIBLE (-325 5200);
FORCEADD Q_RES..1
(-575 5300);
FORCEPROP 1 LAST LOCATION R414
J 0
(-825 5300);
DISPLAY 0.489362 (-825 5300);
PAINT SKYBLUE (-825 5300);
FORCEPROP 0 LAST $SEC 1
J 0
(-450 5325);
DISPLAY 0.680851 (-450 5325);
PAINT MONO (-450 5325);
DISPLAY INVISIBLE (-450 5325);
FORCEPROP 0 LAST CDS_SEC 1
J 0
(-450 5325);
DISPLAY 0.680851 (-450 5325);
DISPLAY INVISIBLE (-450 5325);
FORCEPROP 1 LASTPIN (-675 5300) $PN 1
J 0
(-663 5312);
DISPLAY 0.489362 (-663 5312);
PAINT MONO (-663 5312);
FORCEPROP 1 LASTPIN (-475 5300) $PN 2
J 0
(-513 5312);
DISPLAY 0.489362 (-513 5312);
PAINT MONO (-513 5312);
FORCEPROP 1 LAST VALUE 2.2K
J 0
(-450 5300);
DISPLAY 0.489362 (-450 5300);
PAINT SKYBLUE (-450 5300);
FORCEPROP 2 LAST CDS_LIB pure_quanta
J 0
(-575 5300);
DISPLAY INVISIBLE (-575 5300);
FORCEPROP 1 LAST PATH I385
J 0
(-625 5450);
DISPLAY 0.978723 (-625 5450);
PAINT WHITE (-625 5450);
DISPLAY INVISIBLE (-625 5450);
FORCEPROP 1 LAST WATTAGE 1/16W
J 2
(-600 5150);
DISPLAY 0.978723 (-600 5150);
PAINT SKYBLUE (-600 5150);
DISPLAY INVISIBLE (-600 5150);
FORCEPROP 1 LAST MATERIAL CHIP
J 0
(-575 5150);
DISPLAY 0.978723 (-575 5150);
PAINT SKYBLUE (-575 5150);
DISPLAY INVISIBLE (-575 5150);
FORCEPROP 1 LAST TOLERANCE 5%
J 0
(-575 5200);
DISPLAY 0.978723 (-575 5200);
PAINT SKYBLUE (-575 5200);
DISPLAY INVISIBLE (-575 5200);
FORCEPROP 1 LAST PART_NUMBER CS22202JB07
J 0
(-625 5400);
DISPLAY 0.978723 (-625 5400);
PAINT SKYBLUE (-625 5400);
DISPLAY INVISIBLE (-625 5400);
FORCEPROP 1 LAST PACK_TYPE 0402LF
J 0
(-325 5150);
DISPLAY 0.978723 (-325 5150);
PAINT SKYBLUE (-325 5150);
DISPLAY INVISIBLE (-325 5150);
FORCEADD Q_RES..1
(-575 5250);
FORCEPROP 1 LAST LOCATION R415
J 0
(-825 5250);
DISPLAY 0.489362 (-825 5250);
PAINT SKYBLUE (-825 5250);
FORCEPROP 0 LAST $SEC 1
J 0
(-450 5275);
DISPLAY 0.680851 (-450 5275);
PAINT MONO (-450 5275);
DISPLAY INVISIBLE (-450 5275);
FORCEPROP 0 LAST CDS_SEC 1
J 0
(-450 5275);
DISPLAY 0.680851 (-450 5275);
DISPLAY INVISIBLE (-450 5275);
FORCEPROP 1 LASTPIN (-675 5250) $PN 1
J 0
(-663 5262);
DISPLAY 0.489362 (-663 5262);
PAINT MONO (-663 5262);
FORCEPROP 1 LASTPIN (-475 5250) $PN 2
J 0
(-513 5262);
DISPLAY 0.489362 (-513 5262);
PAINT MONO (-513 5262);
FORCEPROP 1 LAST VALUE 2.2K
J 0
(-450 5250);
DISPLAY 0.489362 (-450 5250);
PAINT SKYBLUE (-450 5250);
FORCEPROP 2 LAST CDS_LIB pure_quanta
J 0
(-575 5250);
DISPLAY INVISIBLE (-575 5250);
FORCEPROP 1 LAST PATH I386
J 0
(-625 5400);
DISPLAY 0.978723 (-625 5400);
PAINT WHITE (-625 5400);
DISPLAY INVISIBLE (-625 5400);
FORCEPROP 1 LAST WATTAGE 1/16W
J 2
(-600 5100);
DISPLAY 0.978723 (-600 5100);
PAINT SKYBLUE (-600 5100);
DISPLAY INVISIBLE (-600 5100);
FORCEPROP 1 LAST MATERIAL CHIP
J 0
(-575 5100);
DISPLAY 0.978723 (-575 5100);
PAINT SKYBLUE (-575 5100);
DISPLAY INVISIBLE (-575 5100);
FORCEPROP 1 LAST TOLERANCE 5%
J 0
(-575 5150);
DISPLAY 0.978723 (-575 5150);
PAINT SKYBLUE (-575 5150);
DISPLAY INVISIBLE (-575 5150);
FORCEPROP 1 LAST PART_NUMBER CS22202JB07
J 0
(-625 5350);
DISPLAY 0.978723 (-625 5350);
PAINT SKYBLUE (-625 5350);
DISPLAY INVISIBLE (-625 5350);
FORCEPROP 1 LAST PACK_TYPE 0402LF
J 0
(-325 5100);
DISPLAY 0.978723 (-325 5100);
PAINT SKYBLUE (-325 5100);
DISPLAY INVISIBLE (-325 5100);
FORCEADD Q_RES..1
(-575 5200);
FORCEPROP 1 LAST LOCATION R416
J 0
(-825 5200);
DISPLAY 0.489362 (-825 5200);
PAINT SKYBLUE (-825 5200);
FORCEPROP 0 LAST $SEC 1
J 0
(-450 5225);
DISPLAY 0.680851 (-450 5225);
PAINT MONO (-450 5225);
DISPLAY INVISIBLE (-450 5225);
FORCEPROP 0 LAST CDS_SEC 1
J 0
(-450 5225);
DISPLAY 0.680851 (-450 5225);
DISPLAY INVISIBLE (-450 5225);
FORCEPROP 1 LASTPIN (-675 5200) $PN 1
J 0
(-663 5212);
DISPLAY 0.489362 (-663 5212);
PAINT MONO (-663 5212);
FORCEPROP 1 LASTPIN (-475 5200) $PN 2
J 0
(-513 5212);
DISPLAY 0.489362 (-513 5212);
PAINT MONO (-513 5212);
FORCEPROP 1 LAST VALUE 2.2K
J 0
(-450 5200);
DISPLAY 0.489362 (-450 5200);
PAINT SKYBLUE (-450 5200);
FORCEPROP 2 LAST CDS_LIB pure_quanta
J 0
(-575 5200);
DISPLAY INVISIBLE (-575 5200);
FORCEPROP 1 LAST PATH I387
J 0
(-625 5350);
DISPLAY 0.978723 (-625 5350);
PAINT WHITE (-625 5350);
DISPLAY INVISIBLE (-625 5350);
FORCEPROP 1 LAST WATTAGE 1/16W
J 2
(-600 5050);
DISPLAY 0.978723 (-600 5050);
PAINT SKYBLUE (-600 5050);
DISPLAY INVISIBLE (-600 5050);
FORCEPROP 1 LAST MATERIAL CHIP
J 0
(-575 5050);
DISPLAY 0.978723 (-575 5050);
PAINT SKYBLUE (-575 5050);
DISPLAY INVISIBLE (-575 5050);
FORCEPROP 1 LAST TOLERANCE 5%
J 0
(-575 5100);
DISPLAY 0.978723 (-575 5100);
PAINT SKYBLUE (-575 5100);
DISPLAY INVISIBLE (-575 5100);
FORCEPROP 1 LAST PART_NUMBER CS22202JB07
J 0
(-625 5300);
DISPLAY 0.978723 (-625 5300);
PAINT SKYBLUE (-625 5300);
DISPLAY INVISIBLE (-625 5300);
FORCEPROP 1 LAST PACK_TYPE 0402LF
J 0
(-325 5050);
DISPLAY 0.978723 (-325 5050);
PAINT SKYBLUE (-325 5050);
DISPLAY INVISIBLE (-325 5050);
FORCEADD Q_RES..1
(-8700 2850);
FORCEPROP 1 LAST LOCATION R387
J 0
(-8950 2850);
DISPLAY 0.489362 (-8950 2850);
PAINT SKYBLUE (-8950 2850);
FORCEPROP 0 LAST $SEC 1
J 0
(-8575 2875);
DISPLAY 0.680851 (-8575 2875);
PAINT MONO (-8575 2875);
DISPLAY INVISIBLE (-8575 2875);
FORCEPROP 0 LAST CDS_SEC 1
J 0
(-8575 2875);
DISPLAY 0.680851 (-8575 2875);
DISPLAY INVISIBLE (-8575 2875);
FORCEPROP 1 LASTPIN (-8800 2850) $PN 1
J 0
(-8788 2862);
DISPLAY 0.489362 (-8788 2862);
PAINT MONO (-8788 2862);
FORCEPROP 1 LASTPIN (-8600 2850) $PN 2
J 0
(-8638 2862);
DISPLAY 0.489362 (-8638 2862);
PAINT MONO (-8638 2862);
FORCEPROP 1 LAST VALUE 2.2K
J 0
(-8575 2850);
DISPLAY 0.489362 (-8575 2850);
PAINT SKYBLUE (-8575 2850);
FORCEPROP 2 LAST CDS_LIB pure_quanta
J 0
(-8700 2850);
DISPLAY INVISIBLE (-8700 2850);
FORCEPROP 1 LAST PATH I388
J 0
(-8750 3000);
DISPLAY 0.978723 (-8750 3000);
PAINT WHITE (-8750 3000);
DISPLAY INVISIBLE (-8750 3000);
FORCEPROP 1 LAST WATTAGE 1/16W
J 2
(-8725 2700);
DISPLAY 0.978723 (-8725 2700);
PAINT SKYBLUE (-8725 2700);
DISPLAY INVISIBLE (-8725 2700);
FORCEPROP 1 LAST MATERIAL CHIP
J 0
(-8700 2700);
DISPLAY 0.978723 (-8700 2700);
PAINT SKYBLUE (-8700 2700);
DISPLAY INVISIBLE (-8700 2700);
FORCEPROP 1 LAST TOLERANCE 5%
J 0
(-8700 2750);
DISPLAY 0.978723 (-8700 2750);
PAINT SKYBLUE (-8700 2750);
DISPLAY INVISIBLE (-8700 2750);
FORCEPROP 1 LAST PART_NUMBER CS22202JB07
J 0
(-8750 2950);
DISPLAY 0.978723 (-8750 2950);
PAINT SKYBLUE (-8750 2950);
DISPLAY INVISIBLE (-8750 2950);
FORCEPROP 1 LAST PACK_TYPE 0402LF
J 0
(-8450 2700);
DISPLAY 0.978723 (-8450 2700);
PAINT SKYBLUE (-8450 2700);
DISPLAY INVISIBLE (-8450 2700);
FORCEADD Q_RES..1
(-8700 2900);
FORCEPROP 1 LAST LOCATION R388
J 0
(-8950 2900);
DISPLAY 0.489362 (-8950 2900);
PAINT SKYBLUE (-8950 2900);
FORCEPROP 0 LAST $SEC 1
J 0
(-8575 2925);
DISPLAY 0.680851 (-8575 2925);
PAINT MONO (-8575 2925);
DISPLAY INVISIBLE (-8575 2925);
FORCEPROP 0 LAST CDS_SEC 1
J 0
(-8575 2925);
DISPLAY 0.680851 (-8575 2925);
DISPLAY INVISIBLE (-8575 2925);
FORCEPROP 1 LASTPIN (-8800 2900) $PN 1
J 0
(-8788 2912);
DISPLAY 0.489362 (-8788 2912);
PAINT MONO (-8788 2912);
FORCEPROP 1 LASTPIN (-8600 2900) $PN 2
J 0
(-8638 2912);
DISPLAY 0.489362 (-8638 2912);
PAINT MONO (-8638 2912);
FORCEPROP 1 LAST VALUE 2.2K
J 0
(-8575 2900);
DISPLAY 0.489362 (-8575 2900);
PAINT SKYBLUE (-8575 2900);
FORCEPROP 2 LAST CDS_LIB pure_quanta
J 0
(-8700 2900);
DISPLAY INVISIBLE (-8700 2900);
FORCEPROP 1 LAST PATH I389
J 0
(-8750 3050);
DISPLAY 0.978723 (-8750 3050);
PAINT WHITE (-8750 3050);
DISPLAY INVISIBLE (-8750 3050);
FORCEPROP 1 LAST WATTAGE 1/16W
J 2
(-8725 2750);
DISPLAY 0.978723 (-8725 2750);
PAINT SKYBLUE (-8725 2750);
DISPLAY INVISIBLE (-8725 2750);
FORCEPROP 1 LAST MATERIAL CHIP
J 0
(-8700 2750);
DISPLAY 0.978723 (-8700 2750);
PAINT SKYBLUE (-8700 2750);
DISPLAY INVISIBLE (-8700 2750);
FORCEPROP 1 LAST TOLERANCE 5%
J 0
(-8700 2800);
DISPLAY 0.978723 (-8700 2800);
PAINT SKYBLUE (-8700 2800);
DISPLAY INVISIBLE (-8700 2800);
FORCEPROP 1 LAST PART_NUMBER CS22202JB07
J 0
(-8750 3000);
DISPLAY 0.978723 (-8750 3000);
PAINT SKYBLUE (-8750 3000);
DISPLAY INVISIBLE (-8750 3000);
FORCEPROP 1 LAST PACK_TYPE 0402LF
J 0
(-8450 2750);
DISPLAY 0.978723 (-8450 2750);
PAINT SKYBLUE (-8450 2750);
DISPLAY INVISIBLE (-8450 2750);
FORCEADD Q_RES..1
(-8700 2950);
FORCEPROP 1 LAST LOCATION R390
J 0
(-8950 2950);
DISPLAY 0.489362 (-8950 2950);
PAINT SKYBLUE (-8950 2950);
FORCEPROP 0 LAST $SEC 1
J 0
(-8575 2975);
DISPLAY 0.680851 (-8575 2975);
PAINT MONO (-8575 2975);
DISPLAY INVISIBLE (-8575 2975);
FORCEPROP 0 LAST CDS_SEC 1
J 0
(-8575 2975);
DISPLAY 0.680851 (-8575 2975);
DISPLAY INVISIBLE (-8575 2975);
FORCEPROP 1 LASTPIN (-8800 2950) $PN 1
J 0
(-8788 2962);
DISPLAY 0.489362 (-8788 2962);
PAINT MONO (-8788 2962);
FORCEPROP 1 LASTPIN (-8600 2950) $PN 2
J 0
(-8638 2962);
DISPLAY 0.489362 (-8638 2962);
PAINT MONO (-8638 2962);
FORCEPROP 1 LAST VALUE 2.2K
J 0
(-8575 2950);
DISPLAY 0.489362 (-8575 2950);
PAINT SKYBLUE (-8575 2950);
FORCEPROP 2 LAST CDS_LIB pure_quanta
J 0
(-8700 2950);
DISPLAY INVISIBLE (-8700 2950);
FORCEPROP 1 LAST PATH I390
J 0
(-8750 3100);
DISPLAY 0.978723 (-8750 3100);
PAINT WHITE (-8750 3100);
DISPLAY INVISIBLE (-8750 3100);
FORCEPROP 1 LAST WATTAGE 1/16W
J 2
(-8725 2800);
DISPLAY 0.978723 (-8725 2800);
PAINT SKYBLUE (-8725 2800);
DISPLAY INVISIBLE (-8725 2800);
FORCEPROP 1 LAST MATERIAL CHIP
J 0
(-8700 2800);
DISPLAY 0.978723 (-8700 2800);
PAINT SKYBLUE (-8700 2800);
DISPLAY INVISIBLE (-8700 2800);
FORCEPROP 1 LAST TOLERANCE 5%
J 0
(-8700 2850);
DISPLAY 0.978723 (-8700 2850);
PAINT SKYBLUE (-8700 2850);
DISPLAY INVISIBLE (-8700 2850);
FORCEPROP 1 LAST PART_NUMBER CS22202JB07
J 0
(-8750 3050);
DISPLAY 0.978723 (-8750 3050);
PAINT SKYBLUE (-8750 3050);
DISPLAY INVISIBLE (-8750 3050);
FORCEPROP 1 LAST PACK_TYPE 0402LF
J 0
(-8450 2800);
DISPLAY 0.978723 (-8450 2800);
PAINT SKYBLUE (-8450 2800);
DISPLAY INVISIBLE (-8450 2800);
FORCEADD Q_RES..1
(-8700 3000);
FORCEPROP 1 LAST LOCATION R389
J 0
(-8950 3000);
DISPLAY 0.489362 (-8950 3000);
PAINT SKYBLUE (-8950 3000);
FORCEPROP 0 LAST $SEC 1
J 0
(-8575 3025);
DISPLAY 0.680851 (-8575 3025);
PAINT MONO (-8575 3025);
DISPLAY INVISIBLE (-8575 3025);
FORCEPROP 0 LAST CDS_SEC 1
J 0
(-8575 3025);
DISPLAY 0.680851 (-8575 3025);
DISPLAY INVISIBLE (-8575 3025);
FORCEPROP 1 LASTPIN (-8800 3000) $PN 1
J 0
(-8788 3012);
DISPLAY 0.489362 (-8788 3012);
PAINT MONO (-8788 3012);
FORCEPROP 1 LASTPIN (-8600 3000) $PN 2
J 0
(-8638 3012);
DISPLAY 0.489362 (-8638 3012);
PAINT MONO (-8638 3012);
FORCEPROP 1 LAST VALUE 2.2K
J 0
(-8575 3000);
DISPLAY 0.489362 (-8575 3000);
PAINT SKYBLUE (-8575 3000);
FORCEPROP 2 LAST CDS_LIB pure_quanta
J 0
(-8700 3000);
DISPLAY INVISIBLE (-8700 3000);
FORCEPROP 1 LAST PATH I391
J 0
(-8750 3150);
DISPLAY 0.978723 (-8750 3150);
PAINT WHITE (-8750 3150);
DISPLAY INVISIBLE (-8750 3150);
FORCEPROP 1 LAST WATTAGE 1/16W
J 2
(-8725 2850);
DISPLAY 0.978723 (-8725 2850);
PAINT SKYBLUE (-8725 2850);
DISPLAY INVISIBLE (-8725 2850);
FORCEPROP 1 LAST MATERIAL CHIP
J 0
(-8700 2850);
DISPLAY 0.978723 (-8700 2850);
PAINT SKYBLUE (-8700 2850);
DISPLAY INVISIBLE (-8700 2850);
FORCEPROP 1 LAST TOLERANCE 5%
J 0
(-8700 2900);
DISPLAY 0.978723 (-8700 2900);
PAINT SKYBLUE (-8700 2900);
DISPLAY INVISIBLE (-8700 2900);
FORCEPROP 1 LAST PART_NUMBER CS22202JB07
J 0
(-8750 3100);
DISPLAY 0.978723 (-8750 3100);
PAINT SKYBLUE (-8750 3100);
DISPLAY INVISIBLE (-8750 3100);
FORCEPROP 1 LAST PACK_TYPE 0402LF
J 0
(-8450 2850);
DISPLAY 0.978723 (-8450 2850);
PAINT SKYBLUE (-8450 2850);
DISPLAY INVISIBLE (-8450 2850);
FORCEADD Q_RES..1
(-8700 3050);
FORCEPROP 1 LAST LOCATION R391
J 0
(-8950 3050);
DISPLAY 0.489362 (-8950 3050);
PAINT SKYBLUE (-8950 3050);
FORCEPROP 0 LAST $SEC 1
J 0
(-8575 3075);
DISPLAY 0.680851 (-8575 3075);
PAINT MONO (-8575 3075);
DISPLAY INVISIBLE (-8575 3075);
FORCEPROP 0 LAST CDS_SEC 1
J 0
(-8575 3075);
DISPLAY 0.680851 (-8575 3075);
DISPLAY INVISIBLE (-8575 3075);
FORCEPROP 1 LASTPIN (-8800 3050) $PN 1
J 0
(-8788 3062);
DISPLAY 0.489362 (-8788 3062);
PAINT MONO (-8788 3062);
FORCEPROP 1 LASTPIN (-8600 3050) $PN 2
J 0
(-8638 3062);
DISPLAY 0.489362 (-8638 3062);
PAINT MONO (-8638 3062);
FORCEPROP 1 LAST VALUE 2.2K
J 0
(-8575 3050);
DISPLAY 0.489362 (-8575 3050);
PAINT SKYBLUE (-8575 3050);
FORCEPROP 2 LAST CDS_LIB pure_quanta
J 0
(-8700 3050);
DISPLAY INVISIBLE (-8700 3050);
FORCEPROP 1 LAST PATH I392
J 0
(-8750 3200);
DISPLAY 0.978723 (-8750 3200);
PAINT WHITE (-8750 3200);
DISPLAY INVISIBLE (-8750 3200);
FORCEPROP 1 LAST WATTAGE 1/16W
J 2
(-8725 2900);
DISPLAY 0.978723 (-8725 2900);
PAINT SKYBLUE (-8725 2900);
DISPLAY INVISIBLE (-8725 2900);
FORCEPROP 1 LAST MATERIAL CHIP
J 0
(-8700 2900);
DISPLAY 0.978723 (-8700 2900);
PAINT SKYBLUE (-8700 2900);
DISPLAY INVISIBLE (-8700 2900);
FORCEPROP 1 LAST TOLERANCE 5%
J 0
(-8700 2950);
DISPLAY 0.978723 (-8700 2950);
PAINT SKYBLUE (-8700 2950);
DISPLAY INVISIBLE (-8700 2950);
FORCEPROP 1 LAST PART_NUMBER CS22202JB07
J 0
(-8750 3150);
DISPLAY 0.978723 (-8750 3150);
PAINT SKYBLUE (-8750 3150);
DISPLAY INVISIBLE (-8750 3150);
FORCEPROP 1 LAST PACK_TYPE 0402LF
J 0
(-8450 2900);
DISPLAY 0.978723 (-8450 2900);
PAINT SKYBLUE (-8450 2900);
DISPLAY INVISIBLE (-8450 2900);
FORCEADD Q_RES..1
(-8700 3100);
FORCEPROP 1 LAST LOCATION R396
J 0
(-8950 3100);
DISPLAY 0.489362 (-8950 3100);
PAINT SKYBLUE (-8950 3100);
FORCEPROP 0 LAST $SEC 1
J 0
(-8575 3125);
DISPLAY 0.680851 (-8575 3125);
PAINT MONO (-8575 3125);
DISPLAY INVISIBLE (-8575 3125);
FORCEPROP 0 LAST CDS_SEC 1
J 0
(-8575 3125);
DISPLAY 0.680851 (-8575 3125);
DISPLAY INVISIBLE (-8575 3125);
FORCEPROP 1 LASTPIN (-8800 3100) $PN 1
J 0
(-8788 3112);
DISPLAY 0.489362 (-8788 3112);
PAINT MONO (-8788 3112);
FORCEPROP 1 LASTPIN (-8600 3100) $PN 2
J 0
(-8638 3112);
DISPLAY 0.489362 (-8638 3112);
PAINT MONO (-8638 3112);
FORCEPROP 1 LAST VALUE 2.2K
J 0
(-8575 3100);
DISPLAY 0.489362 (-8575 3100);
PAINT SKYBLUE (-8575 3100);
FORCEPROP 2 LAST CDS_LIB pure_quanta
J 0
(-8700 3100);
DISPLAY INVISIBLE (-8700 3100);
FORCEPROP 1 LAST PATH I393
J 0
(-8750 3250);
DISPLAY 0.978723 (-8750 3250);
PAINT WHITE (-8750 3250);
DISPLAY INVISIBLE (-8750 3250);
FORCEPROP 1 LAST WATTAGE 1/16W
J 2
(-8725 2950);
DISPLAY 0.978723 (-8725 2950);
PAINT SKYBLUE (-8725 2950);
DISPLAY INVISIBLE (-8725 2950);
FORCEPROP 1 LAST MATERIAL CHIP
J 0
(-8700 2950);
DISPLAY 0.978723 (-8700 2950);
PAINT SKYBLUE (-8700 2950);
DISPLAY INVISIBLE (-8700 2950);
FORCEPROP 1 LAST TOLERANCE 5%
J 0
(-8700 3000);
DISPLAY 0.978723 (-8700 3000);
PAINT SKYBLUE (-8700 3000);
DISPLAY INVISIBLE (-8700 3000);
FORCEPROP 1 LAST PART_NUMBER CS22202JB07
J 0
(-8750 3200);
DISPLAY 0.978723 (-8750 3200);
PAINT SKYBLUE (-8750 3200);
DISPLAY INVISIBLE (-8750 3200);
FORCEPROP 1 LAST PACK_TYPE 0402LF
J 0
(-8450 2950);
DISPLAY 0.978723 (-8450 2950);
PAINT SKYBLUE (-8450 2950);
DISPLAY INVISIBLE (-8450 2950);
FORCEADD Q_RES..1
(-8700 3150);
FORCEPROP 1 LAST LOCATION R397
J 0
(-8950 3150);
DISPLAY 0.489362 (-8950 3150);
PAINT SKYBLUE (-8950 3150);
FORCEPROP 0 LAST $SEC 1
J 0
(-8575 3175);
DISPLAY 0.680851 (-8575 3175);
PAINT MONO (-8575 3175);
DISPLAY INVISIBLE (-8575 3175);
FORCEPROP 0 LAST CDS_SEC 1
J 0
(-8575 3175);
DISPLAY 0.680851 (-8575 3175);
DISPLAY INVISIBLE (-8575 3175);
FORCEPROP 1 LASTPIN (-8800 3150) $PN 1
J 0
(-8788 3162);
DISPLAY 0.489362 (-8788 3162);
PAINT MONO (-8788 3162);
FORCEPROP 1 LASTPIN (-8600 3150) $PN 2
J 0
(-8638 3162);
DISPLAY 0.489362 (-8638 3162);
PAINT MONO (-8638 3162);
FORCEPROP 1 LAST VALUE 2.2K
J 0
(-8575 3150);
DISPLAY 0.489362 (-8575 3150);
PAINT SKYBLUE (-8575 3150);
FORCEPROP 2 LAST CDS_LIB pure_quanta
J 0
(-8700 3150);
DISPLAY INVISIBLE (-8700 3150);
FORCEPROP 1 LAST PATH I394
J 0
(-8750 3300);
DISPLAY 0.978723 (-8750 3300);
PAINT WHITE (-8750 3300);
DISPLAY INVISIBLE (-8750 3300);
FORCEPROP 1 LAST WATTAGE 1/16W
J 2
(-8725 3000);
DISPLAY 0.978723 (-8725 3000);
PAINT SKYBLUE (-8725 3000);
DISPLAY INVISIBLE (-8725 3000);
FORCEPROP 1 LAST MATERIAL CHIP
J 0
(-8700 3000);
DISPLAY 0.978723 (-8700 3000);
PAINT SKYBLUE (-8700 3000);
DISPLAY INVISIBLE (-8700 3000);
FORCEPROP 1 LAST TOLERANCE 5%
J 0
(-8700 3050);
DISPLAY 0.978723 (-8700 3050);
PAINT SKYBLUE (-8700 3050);
DISPLAY INVISIBLE (-8700 3050);
FORCEPROP 1 LAST PART_NUMBER CS22202JB07
J 0
(-8750 3250);
DISPLAY 0.978723 (-8750 3250);
PAINT SKYBLUE (-8750 3250);
DISPLAY INVISIBLE (-8750 3250);
FORCEPROP 1 LAST PACK_TYPE 0402LF
J 0
(-8450 3000);
DISPLAY 0.978723 (-8450 3000);
PAINT SKYBLUE (-8450 3000);
DISPLAY INVISIBLE (-8450 3000);
FORCEADD Q_RES..2
R 2
(-8675 4650);
FORCEPROP 1 LAST LOCATION R392
J 2
(-8725 4725);
DISPLAY 0.489362 (-8725 4725);
PAINT SKYBLUE (-8725 4725);
FORCEPROP 0 LAST $SEC 1
J 0
(-8725 4750);
DISPLAY 0.680851 (-8725 4750);
PAINT MONO (-8725 4750);
DISPLAY INVISIBLE (-8725 4750);
FORCEPROP 0 LAST CDS_SEC 1
J 0
(-8725 4750);
DISPLAY 0.680851 (-8725 4750);
DISPLAY INVISIBLE (-8725 4750);
FORCEPROP 1 LASTPIN (-8675 4750) $PN 1
J 2
(-8680 4712);
DISPLAY 0.489362 (-8680 4712);
PAINT MONO (-8680 4712);
FORCEPROP 1 LASTPIN (-8675 4550) $PN 2
J 2
(-8680 4560);
DISPLAY 0.489362 (-8680 4560);
PAINT MONO (-8680 4560);
FORCEPROP 1 LAST MATERIAL EMPTY
J 2
(-8725 4625);
DISPLAY 0.489362 (-8725 4625);
PAINT RED (-8725 4625);
FORCEPROP 1 LAST VALUE 2.2K
J 2
(-8725 4675);
DISPLAY 0.489362 (-8725 4675);
PAINT SKYBLUE (-8725 4675);
FORCEPROP 1 LAST PACK_TYPE 0402LF
J 2
(-8725 4575);
DISPLAY 0.489362 (-8725 4575);
PAINT SKYBLUE (-8725 4575);
FORCEPROP 2 LAST CDS_LIB pure_quanta
J 2
(-8675 4650);
DISPLAY INVISIBLE (-8675 4650);
FORCEPROP 1 LAST PATH I395
J 2
(-8725 4825);
DISPLAY 0.978723 (-8725 4825);
PAINT WHITE (-8725 4825);
DISPLAY INVISIBLE (-8725 4825);
FORCEPROP 1 LAST WATTAGE 1/16W
J 2
(-8715 4625);
DISPLAY 0.510638 (-8715 4625);
PAINT SKYBLUE (-8715 4625);
DISPLAY INVISIBLE (-8715 4625);
FORCEPROP 1 LAST TOLERANCE 5%
J 2
(-8720 4675);
DISPLAY 0.510638 (-8720 4675);
PAINT SKYBLUE (-8720 4675);
DISPLAY INVISIBLE (-8720 4675);
FORCEPROP 1 LAST PART_NUMBER CS22202JB07
J 2
(-8715 4525);
DISPLAY 0.510638 (-8715 4525);
PAINT SKYBLUE (-8715 4525);
DISPLAY INVISIBLE (-8715 4525);
FORCEADD Q_RES..2
R 2
(-8675 4350);
FORCEPROP 1 LAST LOCATION R393
J 2
(-8725 4425);
DISPLAY 0.489362 (-8725 4425);
PAINT SKYBLUE (-8725 4425);
FORCEPROP 0 LAST $SEC 1
J 0
(-8725 4450);
DISPLAY 0.680851 (-8725 4450);
PAINT MONO (-8725 4450);
DISPLAY INVISIBLE (-8725 4450);
FORCEPROP 0 LAST CDS_SEC 1
J 0
(-8725 4450);
DISPLAY 0.680851 (-8725 4450);
DISPLAY INVISIBLE (-8725 4450);
FORCEPROP 1 LASTPIN (-8675 4450) $PN 1
J 2
(-8680 4412);
DISPLAY 0.489362 (-8680 4412);
PAINT MONO (-8680 4412);
FORCEPROP 1 LASTPIN (-8675 4250) $PN 2
J 2
(-8680 4260);
DISPLAY 0.489362 (-8680 4260);
PAINT MONO (-8680 4260);
FORCEPROP 1 LAST MATERIAL CHIP
J 2
(-8725 4325);
DISPLAY 0.489362 (-8725 4325);
PAINT SKYBLUE (-8725 4325);
FORCEPROP 1 LAST VALUE 2.2K
J 2
(-8725 4375);
DISPLAY 0.489362 (-8725 4375);
PAINT SKYBLUE (-8725 4375);
FORCEPROP 1 LAST PACK_TYPE 0402LF
J 2
(-8725 4275);
DISPLAY 0.489362 (-8725 4275);
PAINT SKYBLUE (-8725 4275);
FORCEPROP 2 LAST CDS_LIB pure_quanta
J 0
(-8675 4350);
DISPLAY INVISIBLE (-8675 4350);
FORCEPROP 1 LAST PATH I396
J 2
(-8725 4525);
DISPLAY 0.978723 (-8725 4525);
PAINT WHITE (-8725 4525);
DISPLAY INVISIBLE (-8725 4525);
FORCEPROP 1 LAST WATTAGE 1/16W
J 2
(-8715 4325);
DISPLAY 0.510638 (-8715 4325);
PAINT SKYBLUE (-8715 4325);
DISPLAY INVISIBLE (-8715 4325);
FORCEPROP 1 LAST TOLERANCE 5%
J 2
(-8720 4375);
DISPLAY 0.510638 (-8720 4375);
PAINT SKYBLUE (-8720 4375);
DISPLAY INVISIBLE (-8720 4375);
FORCEPROP 1 LAST PART_NUMBER CS22202JB07
J 2
(-8715 4225);
DISPLAY 0.510638 (-8715 4225);
PAINT SKYBLUE (-8715 4225);
DISPLAY INVISIBLE (-8715 4225);
FORCEADD Q_RES..2
(-8550 4350);
FORCEPROP 1 LAST LOCATION R394
J 0
(-8500 4425);
DISPLAY 0.489362 (-8500 4425);
PAINT SKYBLUE (-8500 4425);
FORCEPROP 0 LAST $SEC 1
J 0
(-8500 4450);
DISPLAY 0.680851 (-8500 4450);
PAINT MONO (-8500 4450);
DISPLAY INVISIBLE (-8500 4450);
FORCEPROP 0 LAST CDS_SEC 1
J 0
(-8500 4450);
DISPLAY 0.680851 (-8500 4450);
DISPLAY INVISIBLE (-8500 4450);
FORCEPROP 1 LASTPIN (-8550 4450) $PN 1
J 0
(-8545 4412);
DISPLAY 0.489362 (-8545 4412);
PAINT MONO (-8545 4412);
FORCEPROP 1 LASTPIN (-8550 4250) $PN 2
J 0
(-8545 4260);
DISPLAY 0.489362 (-8545 4260);
PAINT MONO (-8545 4260);
FORCEPROP 1 LAST MATERIAL CHIP
J 0
(-8500 4325);
DISPLAY 0.489362 (-8500 4325);
PAINT SKYBLUE (-8500 4325);
FORCEPROP 1 LAST VALUE 2.2K
J 0
(-8500 4375);
DISPLAY 0.489362 (-8500 4375);
PAINT SKYBLUE (-8500 4375);
FORCEPROP 1 LAST PACK_TYPE 0402LF
J 0
(-8500 4275);
DISPLAY 0.489362 (-8500 4275);
PAINT SKYBLUE (-8500 4275);
FORCEPROP 2 LAST CDS_LIB pure_quanta
J 2
(-8550 4350);
DISPLAY INVISIBLE (-8550 4350);
FORCEPROP 1 LAST PATH I397
J 0
(-8500 4525);
DISPLAY 0.978723 (-8500 4525);
PAINT WHITE (-8500 4525);
DISPLAY INVISIBLE (-8500 4525);
FORCEPROP 1 LAST WATTAGE 1/16W
J 0
(-8510 4325);
DISPLAY 0.510638 (-8510 4325);
PAINT SKYBLUE (-8510 4325);
DISPLAY INVISIBLE (-8510 4325);
FORCEPROP 1 LAST TOLERANCE 5%
J 0
(-8505 4375);
DISPLAY 0.510638 (-8505 4375);
PAINT SKYBLUE (-8505 4375);
DISPLAY INVISIBLE (-8505 4375);
FORCEPROP 1 LAST PART_NUMBER CS22202JB07
J 0
(-8510 4225);
DISPLAY 0.510638 (-8510 4225);
PAINT SKYBLUE (-8510 4225);
DISPLAY INVISIBLE (-8510 4225);
FORCEADD OFFPAGE..2
(-1975 4725);
FORCEPROP 2 LAST $XR1 81 
J 0
(-1696 4725);
DISPLAY 0.638298 (-1696 4725);
PAINT MONO (-1696 4725);
FORCEPROP 2 LAST $XR0 27 
J 0
(-1786 4725);
DISPLAY 0.638298 (-1786 4725);
PAINT MONO (-1786 4725);
FORCEPROP 2 LAST CDS_LIB standard
J 0
(-1975 4725);
DISPLAY INVISIBLE (-1975 4725);
FORCEPROP 1 LAST OFFPAGE TRUE
J 0
(-1650 4600);
DISPLAY 0.872340 (-1650 4600);
PAINT GREEN (-1650 4600);
DISPLAY INVISIBLE (-1650 4600);
FORCEPROP 1 LAST COMMENT_BODY TRUE
J 0
(-2020 4630);
DISPLAY 0.872340 (-2020 4630);
PAINT GREEN (-2020 4630);
DISPLAY INVISIBLE (-2020 4630);
FORCEPROP 2 LAST PATH I398
J 0
(-1800 4800);
DISPLAY 0.680851 (-1800 4800);
DISPLAY INVISIBLE (-1800 4800);
FORCEADD Q_RES..1
(-2725 4725);
FORCEPROP 1 LAST LOCATION R489
J 0
(-2625 4725);
DISPLAY 0.489362 (-2625 4725);
PAINT SKYBLUE (-2625 4725);
FORCEPROP 2 LAST $SEC 1
J 0
(-2775 4925);
DISPLAY 0.680851 (-2775 4925);
PAINT MONO (-2775 4925);
DISPLAY INVISIBLE (-2775 4925);
FORCEPROP 2 LAST CDS_SEC 1
J 0
(-2775 4925);
DISPLAY 0.680851 (-2775 4925);
DISPLAY INVISIBLE (-2775 4925);
FORCEPROP 1 LASTPIN (-2825 4725) $PN 1
J 0
(-2813 4737);
DISPLAY 0.489362 (-2813 4737);
PAINT MONO (-2813 4737);
FORCEPROP 1 LASTPIN (-2625 4725) $PN 2
J 0
(-2663 4737);
DISPLAY 0.489362 (-2663 4737);
PAINT MONO (-2663 4737);
FORCEPROP 1 LAST VALUE 33
J 2
(-2850 4725);
DISPLAY 0.489362 (-2850 4725);
PAINT SKYBLUE (-2850 4725);
FORCEPROP 2 LAST BOM_COST MEM
J 2
(-2700 4875);
DISPLAY 0.744681 (-2700 4875);
PAINT WHITE (-2700 4875);
DISPLAY INVISIBLE (-2700 4875);
FORCEPROP 2 LAST CDS_LIB pure_quanta
J 0
(-2725 4725);
DISPLAY INVISIBLE (-2725 4725);
FORCEPROP 1 LAST PATH I399
J 0
(-2775 4875);
DISPLAY 0.978723 (-2775 4875);
PAINT WHITE (-2775 4875);
DISPLAY INVISIBLE (-2775 4875);
FORCEPROP 1 LAST WATTAGE 1/16W
J 2
(-2800 4650);
DISPLAY 0.489362 (-2800 4650);
PAINT SKYBLUE (-2800 4650);
DISPLAY INVISIBLE (-2800 4650);
FORCEPROP 1 LAST MATERIAL CHIP
J 2
(-2550 4700);
DISPLAY 0.489362 (-2550 4700);
PAINT SKYBLUE (-2550 4700);
DISPLAY INVISIBLE (-2550 4700);
FORCEPROP 1 LAST TOLERANCE 5%
J 0
(-2850 4700);
DISPLAY 0.489362 (-2850 4700);
PAINT SKYBLUE (-2850 4700);
DISPLAY INVISIBLE (-2850 4700);
FORCEPROP 1 LAST PART_NUMBER CS03302JB29
J 2
(-2625 4775);
DISPLAY 0.489362 (-2625 4775);
PAINT SKYBLUE (-2625 4775);
DISPLAY INVISIBLE (-2625 4775);
FORCEPROP 1 LAST PACK_TYPE 0402LF
J 2
(-2550 4650);
DISPLAY 0.489362 (-2550 4650);
PAINT SKYBLUE (-2550 4650);
DISPLAY INVISIBLE (-2550 4650);
FORCEPROP 2 LAST ROOM RST_CPU0_PLD_TO_DIMM
J 2
(-2700 4825);
DISPLAY 0.744681 (-2700 4825);
PAINT RED (-2700 4825);
DISPLAY INVISIBLE (-2700 4825);
FORCEADD OFFPAGE..2
(-1975 4875);
FORCEPROP 2 LAST $XR0 80 
J 0
(-1786 4875);
DISPLAY 0.638298 (-1786 4875);
PAINT MONO (-1786 4875);
FORCEPROP 2 LAST CDS_LIB standard
J 2
(-1975 4875);
DISPLAY INVISIBLE (-1975 4875);
FORCEPROP 2 LAST PATH I400
J 0
(-1675 4925);
DISPLAY 0.680851 (-1675 4925);
DISPLAY INVISIBLE (-1675 4925);
FORCEPROP 1 LAST COMMENT_BODY TRUE
J 0
(-2020 4780);
DISPLAY 0.872340 (-2020 4780);
PAINT GREEN (-2020 4780);
DISPLAY INVISIBLE (-2020 4780);
FORCEPROP 1 LAST OFFPAGE TRUE
J 0
(-1650 4750);
DISPLAY 0.872340 (-1650 4750);
PAINT GREEN (-1650 4750);
DISPLAY INVISIBLE (-1650 4750);
FORCEADD Q_RES..1
(-2725 4875);
FORCEPROP 1 LAST LOCATION R247
J 0
(-2600 4875);
DISPLAY 0.489362 (-2600 4875);
PAINT SKYBLUE (-2600 4875);
FORCEPROP 0 LAST $SEC 1
J 2
(-2600 4925);
DISPLAY 0.680851 (-2600 4925);
PAINT MONO (-2600 4925);
DISPLAY INVISIBLE (-2600 4925);
FORCEPROP 0 LAST CDS_SEC 1
J 2
(-2600 4925);
DISPLAY 1.021277 (-2600 4925);
DISPLAY INVISIBLE (-2600 4925);
FORCEPROP 1 LASTPIN (-2825 4875) $PN 1
J 0
(-2813 4887);
DISPLAY 0.489362 (-2813 4887);
PAINT MONO (-2813 4887);
FORCEPROP 1 LASTPIN (-2625 4875) $PN 2
J 0
(-2663 4887);
DISPLAY 0.489362 (-2663 4887);
PAINT MONO (-2663 4887);
FORCEPROP 1 LAST VALUE 33
J 2
(-2850 4875);
DISPLAY 0.489362 (-2850 4875);
PAINT SKYBLUE (-2850 4875);
FORCEPROP 2 LAST CDS_LIB pure_quanta
J 2
(-2725 4875);
DISPLAY INVISIBLE (-2725 4875);
FORCEPROP 2 LAST BOM_COST MEM
J 2
(-2700 5025);
DISPLAY 0.744681 (-2700 5025);
PAINT WHITE (-2700 5025);
DISPLAY INVISIBLE (-2700 5025);
FORCEPROP 1 LAST PATH I401
J 0
(-2775 5025);
DISPLAY 0.978723 (-2775 5025);
PAINT WHITE (-2775 5025);
DISPLAY INVISIBLE (-2775 5025);
FORCEPROP 1 LAST WATTAGE 1/16W
J 2
(-2800 4800);
DISPLAY 0.489362 (-2800 4800);
PAINT SKYBLUE (-2800 4800);
DISPLAY INVISIBLE (-2800 4800);
FORCEPROP 1 LAST MATERIAL CHIP
J 2
(-2550 4850);
DISPLAY 0.489362 (-2550 4850);
PAINT SKYBLUE (-2550 4850);
DISPLAY INVISIBLE (-2550 4850);
FORCEPROP 1 LAST TOLERANCE 5%
J 0
(-2850 4850);
DISPLAY 0.489362 (-2850 4850);
PAINT SKYBLUE (-2850 4850);
DISPLAY INVISIBLE (-2850 4850);
FORCEPROP 1 LAST PART_NUMBER CS03302JB29
J 2
(-2625 4925);
DISPLAY 0.489362 (-2625 4925);
PAINT SKYBLUE (-2625 4925);
DISPLAY INVISIBLE (-2625 4925);
FORCEPROP 1 LAST PACK_TYPE 0402LF
J 2
(-2550 4800);
DISPLAY 0.489362 (-2550 4800);
PAINT SKYBLUE (-2550 4800);
DISPLAY INVISIBLE (-2550 4800);
FORCEPROP 2 LAST ROOM RST_CPU0_PLD_TO_DIMM
J 2
(-2700 4975);
DISPLAY 0.744681 (-2700 4975);
PAINT RED (-2700 4975);
DISPLAY INVISIBLE (-2700 4975);
FORCEADD TP..1
R 4
(-5900 1625);
FORCEPROP 1 LAST LOCATION TP10
J 1
(-5900 1525);
DISPLAY 0.489362 (-5900 1525);
PAINT SKYBLUE (-5900 1525);
FORCEPROP 0 LAST $SEC 1
J 0
(-5925 1600);
DISPLAY 0.680851 (-5925 1600);
PAINT MONO (-5925 1600);
DISPLAY INVISIBLE (-5925 1600);
FORCEPROP 0 LAST CDS_SEC 1
J 0
(-5925 1600);
DISPLAY 0.680851 (-5925 1600);
DISPLAY INVISIBLE (-5925 1600);
FORCEPROP 0 LASTPIN (-5900 1675) $PN 1
R 1
J 0
(-5910 1685);
DISPLAY 0.489362 (-5910 1685);
PAINT MONO (-5910 1685);
FORCEPROP 1 LAST MATERIAL NA
J 0
(-5925 1575);
DISPLAY 0.489362 (-5925 1575);
PAINT SKYBLUE (-5925 1575);
FORCEPROP 1 LASTPIN (-5900 1675) $PIN_NUMBER ?
R 2
J 2
(-5950 1675);
DISPLAY 0.702128 (-5950 1675);
PAINT MONO (-5950 1675);
DISPLAY INVISIBLE (-5950 1675);
FORCEPROP 2 LAST CDS_LIB pure_quanta
J 0
(-5900 1625);
DISPLAY INVISIBLE (-5900 1625);
FORCEPROP 1 LAST PATH I403
R 2
J 1
(-5905 1580);
DISPLAY 0.446809 (-5905 1580);
PAINT GREEN (-5905 1580);
DISPLAY INVISIBLE (-5905 1580);
FORCEPROP 1 LAST PART_NUMBER TP26
R 2
J 1
(-5955 1670);
DISPLAY 0.446809 (-5955 1670);
PAINT SKYBLUE (-5955 1670);
DISPLAY INVISIBLE (-5955 1670);
FORCEPROP 1 LAST PACK_TYPE TP
R 2
J 1
(-5955 1690);
DISPLAY 0.446809 (-5955 1690);
PAINT SKYBLUE (-5955 1690);
DISPLAY INVISIBLE (-5955 1690);
FORCEADD TP..1
R 4
(-6700 1625);
FORCEPROP 1 LAST LOCATION TP1
J 1
(-6700 1525);
DISPLAY 0.489362 (-6700 1525);
PAINT SKYBLUE (-6700 1525);
FORCEPROP 0 LAST $SEC 1
J 0
(-6725 1600);
DISPLAY 0.680851 (-6725 1600);
PAINT MONO (-6725 1600);
DISPLAY INVISIBLE (-6725 1600);
FORCEPROP 0 LAST CDS_SEC 1
J 0
(-6725 1600);
DISPLAY 0.680851 (-6725 1600);
DISPLAY INVISIBLE (-6725 1600);
FORCEPROP 0 LASTPIN (-6700 1675) $PN 1
R 1
J 0
(-6710 1685);
DISPLAY 0.489362 (-6710 1685);
PAINT MONO (-6710 1685);
FORCEPROP 1 LAST MATERIAL NA
J 0
(-6725 1575);
DISPLAY 0.489362 (-6725 1575);
PAINT SKYBLUE (-6725 1575);
FORCEPROP 2 LAST CDS_LIB pure_quanta
R 2
J 0
(-6700 1625);
DISPLAY INVISIBLE (-6700 1625);
FORCEPROP 1 LASTPIN (-6700 1675) $PIN_NUMBER ?
R 2
J 2
(-6750 1675);
DISPLAY 0.702128 (-6750 1675);
PAINT MONO (-6750 1675);
DISPLAY INVISIBLE (-6750 1675);
FORCEPROP 1 LAST PATH I404
R 2
J 1
(-6705 1580);
DISPLAY 0.446809 (-6705 1580);
PAINT GREEN (-6705 1580);
DISPLAY INVISIBLE (-6705 1580);
FORCEPROP 1 LAST PART_NUMBER TP26
R 2
J 1
(-6755 1670);
DISPLAY 0.446809 (-6755 1670);
PAINT SKYBLUE (-6755 1670);
DISPLAY INVISIBLE (-6755 1670);
FORCEPROP 1 LAST PACK_TYPE TP
R 2
J 1
(-6755 1690);
DISPLAY 0.446809 (-6755 1690);
PAINT SKYBLUE (-6755 1690);
DISPLAY INVISIBLE (-6755 1690);
FORCEADD OFFPAGE..2
(-425 3825);
FORCEPROP 2 LAST $XR1 81 
J 0
(-146 3825);
DISPLAY 0.638298 (-146 3825);
PAINT MONO (-146 3825);
FORCEPROP 2 LAST $XR0 54 
J 0
(-236 3825);
DISPLAY 0.638298 (-236 3825);
PAINT MONO (-236 3825);
FORCEPROP 2 LAST CDS_LIB standard
J 0
(-425 3825);
DISPLAY INVISIBLE (-425 3825);
FORCEPROP 2 LAST PATH I405
J 0
(-250 3900);
DISPLAY 0.680851 (-250 3900);
DISPLAY INVISIBLE (-250 3900);
FORCEPROP 1 LAST OFFPAGE TRUE
J 0
(-100 3700);
DISPLAY 0.872340 (-100 3700);
PAINT GREEN (-100 3700);
DISPLAY INVISIBLE (-100 3700);
FORCEPROP 1 LAST COMMENT_BODY TRUE
J 0
(-470 3730);
DISPLAY 0.872340 (-470 3730);
PAINT GREEN (-470 3730);
DISPLAY INVISIBLE (-470 3730);
FORCEADD OFFPAGE..4
R 2
(-1700 3825);
FORCEPROP 2 LAST $XR1 81 
J 0
(-2011 3825);
DISPLAY 0.638298 (-2011 3825);
PAINT MONO (-2011 3825);
FORCEPROP 2 LAST $XR0 27 
J 0
(-1921 3825);
DISPLAY 0.638298 (-1921 3825);
PAINT MONO (-1921 3825);
FORCEPROP 2 LAST CDS_LIB standard
J 0
(-1700 3825);
DISPLAY INVISIBLE (-1700 3825);
FORCEPROP 2 LAST PATH I406
J 0
(-1650 3900);
DISPLAY 0.680851 (-1650 3900);
DISPLAY INVISIBLE (-1650 3900);
FORCEPROP 1 LAST OFFPAGE TRUE
J 2
(-2025 3700);
DISPLAY 0.872340 (-2025 3700);
PAINT GREEN (-2025 3700);
DISPLAY INVISIBLE (-2025 3700);
FORCEPROP 1 LAST COMMENT_BODY TRUE
J 2
(-1675 3725);
DISPLAY 0.872340 (-1675 3725);
PAINT GREEN (-1675 3725);
DISPLAY INVISIBLE (-1675 3725);
FORCEADD Q_RES..1
(-1050 3825);
FORCEPROP 1 LAST $LOCATION R1533
J 0
(-950 3825);
DISPLAY 0.489362 (-950 3825);
PAINT SKYBLUE (-950 3825);
FORCEPROP 0 LAST CDS_LOCATION R1533
J 0
(-950 3850);
DISPLAY 0.680851 (-950 3850);
DISPLAY INVISIBLE (-950 3850);
FORCEPROP 0 LAST $SEC 1
J 0
(-950 3850);
DISPLAY 0.680851 (-950 3850);
PAINT MONO (-950 3850);
DISPLAY INVISIBLE (-950 3850);
FORCEPROP 0 LAST CDS_SEC 1
J 0
(-950 3850);
DISPLAY 0.680851 (-950 3850);
DISPLAY INVISIBLE (-950 3850);
FORCEPROP 1 LASTPIN (-1150 3825) $PN 1
J 0
(-1138 3837);
DISPLAY 0.787234 (-1138 3837);
PAINT MONO (-1138 3837);
FORCEPROP 1 LASTPIN (-950 3825) $PN 2
J 0
(-988 3837);
DISPLAY 0.787234 (-988 3837);
PAINT MONO (-988 3837);
FORCEPROP 1 LAST VALUE 0
J 2
(-1150 3825);
DISPLAY 0.489362 (-1150 3825);
PAINT SKYBLUE (-1150 3825);
FORCEPROP 1 LAST PACK_TYPE 0402LF
J 0
(-1000 3750);
DISPLAY 0.489362 (-1000 3750);
PAINT SKYBLUE (-1000 3750);
DISPLAY INVISIBLE (-1000 3750);
FORCEPROP 1 LAST PART_NUMBER CS00002JB38
J 0
(-1025 3875);
DISPLAY 0.489362 (-1025 3875);
PAINT SKYBLUE (-1025 3875);
DISPLAY INVISIBLE (-1025 3875);
FORCEPROP 1 LAST TOLERANCE 5%
J 0
(-1075 3750);
DISPLAY 0.489362 (-1075 3750);
PAINT SKYBLUE (-1075 3750);
DISPLAY INVISIBLE (-1075 3750);
FORCEPROP 1 LAST MATERIAL CHIP
J 0
(-625 3750);
DISPLAY 0.489362 (-625 3750);
PAINT SKYBLUE (-625 3750);
DISPLAY INVISIBLE (-625 3750);
FORCEPROP 1 LAST WATTAGE 1/16W
J 2
(-650 3750);
DISPLAY 0.489362 (-650 3750);
PAINT SKYBLUE (-650 3750);
DISPLAY INVISIBLE (-650 3750);
FORCEPROP 1 LAST PATH I407
J 0
(-1100 3975);
DISPLAY 0.978723 (-1100 3975);
PAINT WHITE (-1100 3975);
DISPLAY INVISIBLE (-1100 3975);
FORCEPROP 2 LAST CDS_LIB pure_quanta
J 0
(-1050 3825);
DISPLAY INVISIBLE (-1050 3825);
FORCEADD OFFPAGE..4
R 2
(-5750 5425);
FORCEPROP 2 LAST $XR0 169 
J 0
(-6002 5425);
DISPLAY 0.638298 (-6002 5425);
PAINT MONO (-6002 5425);
FORCEPROP 2 LAST CDS_LIB standard
J 0
(-5750 5425);
DISPLAY INVISIBLE (-5750 5425);
FORCEPROP 1 LAST OFFPAGE TRUE
J 2
(-6075 5300);
DISPLAY 0.872340 (-6075 5300);
PAINT GREEN (-6075 5300);
DISPLAY INVISIBLE (-6075 5300);
FORCEPROP 1 LAST COMMENT_BODY TRUE
J 2
(-5725 5325);
DISPLAY 0.872340 (-5725 5325);
PAINT GREEN (-5725 5325);
DISPLAY INVISIBLE (-5725 5325);
FORCEPROP 2 LAST PATH I43
J 0
(-5700 5500);
DISPLAY 1.021277 (-5700 5500);
DISPLAY INVISIBLE (-5700 5500);
FORCEADD OFFPAGE..4
R 2
(-5750 5225);
FORCEPROP 2 LAST $XR0 176 
J 0
(-6002 5225);
DISPLAY 0.638298 (-6002 5225);
PAINT MONO (-6002 5225);
FORCEPROP 2 LAST CDS_LIB standard
J 0
(-5750 5225);
DISPLAY INVISIBLE (-5750 5225);
FORCEPROP 1 LAST OFFPAGE TRUE
J 2
(-6075 5100);
DISPLAY 0.872340 (-6075 5100);
PAINT GREEN (-6075 5100);
DISPLAY INVISIBLE (-6075 5100);
FORCEPROP 1 LAST COMMENT_BODY TRUE
J 2
(-5725 5125);
DISPLAY 0.872340 (-5725 5125);
PAINT GREEN (-5725 5125);
DISPLAY INVISIBLE (-5725 5125);
FORCEPROP 2 LAST PATH I46
J 0
(-5700 5300);
DISPLAY 1.021277 (-5700 5300);
DISPLAY INVISIBLE (-5700 5300);
FORCEADD OFFPAGE..2
R 2
(-6825 1975);
FORCEPROP 2 LAST $XR0 169 
J 0
(-7110 1975);
DISPLAY 0.638298 (-7110 1975);
PAINT MONO (-7110 1975);
FORCEPROP 2 LAST CDS_LIB standard
J 0
(-6825 1975);
DISPLAY INVISIBLE (-6825 1975);
FORCEPROP 1 LAST OFFPAGE TRUE
J 2
(-7150 1850);
DISPLAY 0.872340 (-7150 1850);
PAINT GREEN (-7150 1850);
DISPLAY INVISIBLE (-7150 1850);
FORCEPROP 1 LAST COMMENT_BODY TRUE
J 2
(-6780 1880);
DISPLAY 0.872340 (-6780 1880);
PAINT GREEN (-6780 1880);
DISPLAY INVISIBLE (-6780 1880);
FORCEPROP 2 LAST PATH I47
J 0
(-6775 2050);
DISPLAY 1.021277 (-6775 2050);
DISPLAY INVISIBLE (-6775 2050);
FORCEADD OFFPAGE..2
R 2
(-6825 1775);
FORCEPROP 2 LAST $XR0 169 
J 0
(-7110 1775);
DISPLAY 0.638298 (-7110 1775);
PAINT MONO (-7110 1775);
FORCEPROP 2 LAST CDS_LIB standard
J 0
(-6825 1775);
DISPLAY INVISIBLE (-6825 1775);
FORCEPROP 1 LAST OFFPAGE TRUE
J 2
(-7150 1650);
DISPLAY 0.872340 (-7150 1650);
PAINT GREEN (-7150 1650);
DISPLAY INVISIBLE (-7150 1650);
FORCEPROP 1 LAST COMMENT_BODY TRUE
J 2
(-6780 1680);
DISPLAY 0.872340 (-6780 1680);
PAINT GREEN (-6780 1680);
DISPLAY INVISIBLE (-6780 1680);
FORCEPROP 2 LAST PATH I50
J 0
(-6775 1850);
DISPLAY 1.021277 (-6775 1850);
DISPLAY INVISIBLE (-6775 1850);
FORCEADD OFFPAGE..2
R 2
(-6825 2325);
FORCEPROP 2 LAST $XR0 169 
J 0
(-7110 2325);
DISPLAY 0.638298 (-7110 2325);
PAINT MONO (-7110 2325);
FORCEPROP 2 LAST CDS_LIB standard
J 0
(-6825 2325);
DISPLAY INVISIBLE (-6825 2325);
FORCEPROP 1 LAST OFFPAGE TRUE
J 2
(-7150 2200);
DISPLAY 0.872340 (-7150 2200);
PAINT GREEN (-7150 2200);
DISPLAY INVISIBLE (-7150 2200);
FORCEPROP 1 LAST COMMENT_BODY TRUE
J 2
(-6780 2230);
DISPLAY 0.872340 (-6780 2230);
PAINT GREEN (-6780 2230);
DISPLAY INVISIBLE (-6780 2230);
FORCEPROP 2 LAST PATH I51
J 0
(-6775 2400);
DISPLAY 1.021277 (-6775 2400);
DISPLAY INVISIBLE (-6775 2400);
FORCEADD OFFPAGE..2
R 2
(-6825 2025);
FORCEPROP 2 LAST $XR0 176 
J 0
(-7110 2025);
DISPLAY 0.638298 (-7110 2025);
PAINT MONO (-7110 2025);
FORCEPROP 2 LAST CDS_LIB standard
J 0
(-6825 2025);
DISPLAY INVISIBLE (-6825 2025);
FORCEPROP 1 LAST OFFPAGE TRUE
J 2
(-7150 1900);
DISPLAY 0.872340 (-7150 1900);
PAINT GREEN (-7150 1900);
DISPLAY INVISIBLE (-7150 1900);
FORCEPROP 1 LAST COMMENT_BODY TRUE
J 2
(-6780 1930);
DISPLAY 0.872340 (-6780 1930);
PAINT GREEN (-6780 1930);
DISPLAY INVISIBLE (-6780 1930);
FORCEPROP 2 LAST PATH I53
J 0
(-6775 2100);
DISPLAY 1.021277 (-6775 2100);
DISPLAY INVISIBLE (-6775 2100);
FORCEADD OFFPAGE..2
R 2
(-6825 2225);
FORCEPROP 2 LAST $XR1 183 
J 0
(-7230 2225);
DISPLAY 0.638298 (-7230 2225);
PAINT MONO (-7230 2225);
FORCEPROP 2 LAST $XR0 176 
J 0
(-7110 2225);
DISPLAY 0.638298 (-7110 2225);
PAINT MONO (-7110 2225);
FORCEPROP 2 LAST CDS_LIB standard
J 0
(-6825 2225);
DISPLAY INVISIBLE (-6825 2225);
FORCEPROP 1 LAST OFFPAGE TRUE
J 2
(-7150 2100);
DISPLAY 0.872340 (-7150 2100);
PAINT GREEN (-7150 2100);
DISPLAY INVISIBLE (-7150 2100);
FORCEPROP 1 LAST COMMENT_BODY TRUE
J 2
(-6780 2130);
DISPLAY 0.872340 (-6780 2130);
PAINT GREEN (-6780 2130);
DISPLAY INVISIBLE (-6780 2130);
FORCEPROP 2 LAST PATH I54
J 0
(-6775 2300);
DISPLAY 1.021277 (-6775 2300);
DISPLAY INVISIBLE (-6775 2300);
FORCEADD OFFPAGE..2
R 2
(-6825 2075);
FORCEPROP 2 LAST $XR0 176 
J 0
(-7110 2075);
DISPLAY 0.638298 (-7110 2075);
PAINT MONO (-7110 2075);
FORCEPROP 2 LAST CDS_LIB standard
J 0
(-6825 2075);
DISPLAY INVISIBLE (-6825 2075);
FORCEPROP 1 LAST OFFPAGE TRUE
J 2
(-7150 1950);
DISPLAY 0.872340 (-7150 1950);
PAINT GREEN (-7150 1950);
DISPLAY INVISIBLE (-7150 1950);
FORCEPROP 1 LAST COMMENT_BODY TRUE
J 2
(-6780 1980);
DISPLAY 0.872340 (-6780 1980);
PAINT GREEN (-6780 1980);
DISPLAY INVISIBLE (-6780 1980);
FORCEPROP 2 LAST PATH I55
J 0
(-6775 2150);
DISPLAY 1.021277 (-6775 2150);
DISPLAY INVISIBLE (-6775 2150);
FORCEADD OFFPAGE..2
R 2
(-6825 2275);
FORCEPROP 2 LAST $XR0 176 
J 0
(-7110 2275);
DISPLAY 0.638298 (-7110 2275);
PAINT MONO (-7110 2275);
FORCEPROP 2 LAST CDS_LIB standard
J 0
(-6825 2275);
DISPLAY INVISIBLE (-6825 2275);
FORCEPROP 1 LAST OFFPAGE TRUE
J 2
(-7150 2150);
DISPLAY 0.872340 (-7150 2150);
PAINT GREEN (-7150 2150);
DISPLAY INVISIBLE (-7150 2150);
FORCEPROP 1 LAST COMMENT_BODY TRUE
J 2
(-6780 2180);
DISPLAY 0.872340 (-6780 2180);
PAINT GREEN (-6780 2180);
DISPLAY INVISIBLE (-6780 2180);
FORCEPROP 2 LAST PATH I56
J 0
(-6775 2350);
DISPLAY 1.021277 (-6775 2350);
DISPLAY INVISIBLE (-6775 2350);
FORCEADD OFFPAGE..2
R 2
(-6825 1925);
FORCEPROP 2 LAST $XR0 183 
J 0
(-7110 1925);
DISPLAY 0.638298 (-7110 1925);
PAINT MONO (-7110 1925);
FORCEPROP 2 LAST CDS_LIB standard
J 0
(-6825 1925);
DISPLAY INVISIBLE (-6825 1925);
FORCEPROP 1 LAST OFFPAGE TRUE
J 2
(-7150 1800);
DISPLAY 0.872340 (-7150 1800);
PAINT GREEN (-7150 1800);
DISPLAY INVISIBLE (-7150 1800);
FORCEPROP 1 LAST COMMENT_BODY TRUE
J 2
(-6780 1830);
DISPLAY 0.872340 (-6780 1830);
PAINT GREEN (-6780 1830);
DISPLAY INVISIBLE (-6780 1830);
FORCEPROP 2 LAST PATH I57
J 0
(-6775 2000);
DISPLAY 1.021277 (-6775 2000);
DISPLAY INVISIBLE (-6775 2000);
FORCEADD OFFPAGE..4
R 2
(-6125 4875);
FORCEPROP 2 LAST $XR0 138 
J 0
(-6407 4875);
DISPLAY 0.638298 (-6407 4875);
PAINT MONO (-6407 4875);
FORCEPROP 2 LAST CDS_LIB standard
J 0
(-6125 4875);
DISPLAY INVISIBLE (-6125 4875);
FORCEPROP 1 LAST OFFPAGE TRUE
J 2
(-6450 4750);
DISPLAY 0.872340 (-6450 4750);
PAINT GREEN (-6450 4750);
DISPLAY INVISIBLE (-6450 4750);
FORCEPROP 1 LAST COMMENT_BODY TRUE
J 2
(-6100 4775);
DISPLAY 0.872340 (-6100 4775);
PAINT GREEN (-6100 4775);
DISPLAY INVISIBLE (-6100 4775);
FORCEPROP 2 LAST PATH I62
J 0
(-6075 4950);
DISPLAY 1.021277 (-6075 4950);
DISPLAY INVISIBLE (-6075 4950);
FORCEADD OFFPAGE..4
R 2
(-6125 4825);
FORCEPROP 2 LAST $XR0 138 
J 0
(-6407 4825);
DISPLAY 0.638298 (-6407 4825);
PAINT MONO (-6407 4825);
FORCEPROP 2 LAST CDS_LIB standard
J 0
(-6125 4825);
DISPLAY INVISIBLE (-6125 4825);
FORCEPROP 1 LAST OFFPAGE TRUE
J 2
(-6450 4700);
DISPLAY 0.872340 (-6450 4700);
PAINT GREEN (-6450 4700);
DISPLAY INVISIBLE (-6450 4700);
FORCEPROP 1 LAST COMMENT_BODY TRUE
J 2
(-6100 4725);
DISPLAY 0.872340 (-6100 4725);
PAINT GREEN (-6100 4725);
DISPLAY INVISIBLE (-6100 4725);
FORCEPROP 2 LAST PATH I63
J 0
(-6075 4900);
DISPLAY 1.021277 (-6075 4900);
DISPLAY INVISIBLE (-6075 4900);
FORCEADD OFFPAGE..2
R 2
(-6825 1825);
FORCEPROP 2 LAST $XR0 185 
J 0
(-7110 1825);
DISPLAY 0.638298 (-7110 1825);
PAINT MONO (-7110 1825);
FORCEPROP 2 LAST CDS_LIB standard
J 0
(-6825 1825);
DISPLAY INVISIBLE (-6825 1825);
FORCEPROP 1 LAST OFFPAGE TRUE
J 2
(-7150 1700);
DISPLAY 0.872340 (-7150 1700);
PAINT GREEN (-7150 1700);
DISPLAY INVISIBLE (-7150 1700);
FORCEPROP 1 LAST COMMENT_BODY TRUE
J 2
(-6780 1730);
DISPLAY 0.872340 (-6780 1730);
PAINT GREEN (-6780 1730);
DISPLAY INVISIBLE (-6780 1730);
FORCEPROP 2 LAST PATH I67
J 0
(-6775 1900);
DISPLAY 1.021277 (-6775 1900);
DISPLAY INVISIBLE (-6775 1900);
FORCEADD OFFPAGE..2
R 2
(-6825 2175);
FORCEPROP 2 LAST $XR0 185 
J 0
(-7110 2175);
DISPLAY 0.638298 (-7110 2175);
PAINT MONO (-7110 2175);
FORCEPROP 2 LAST CDS_LIB standard
J 0
(-6825 2175);
DISPLAY INVISIBLE (-6825 2175);
FORCEPROP 1 LAST OFFPAGE TRUE
J 2
(-7150 2050);
DISPLAY 0.872340 (-7150 2050);
PAINT GREEN (-7150 2050);
DISPLAY INVISIBLE (-7150 2050);
FORCEPROP 1 LAST COMMENT_BODY TRUE
J 2
(-6780 2080);
DISPLAY 0.872340 (-6780 2080);
PAINT GREEN (-6780 2080);
DISPLAY INVISIBLE (-6780 2080);
FORCEPROP 2 LAST PATH I68
J 0
(-6775 2250);
DISPLAY 1.021277 (-6775 2250);
DISPLAY INVISIBLE (-6775 2250);
FORCEADD OFFPAGE..4
R 2
(-5750 5675);
FORCEPROP 2 LAST $XR1 82 
J 0
(-6061 5675);
DISPLAY 0.638298 (-6061 5675);
PAINT MONO (-6061 5675);
FORCEPROP 2 LAST $XR0 80 
J 0
(-5971 5675);
DISPLAY 0.638298 (-5971 5675);
PAINT MONO (-5971 5675);
FORCEPROP 2 LAST CDS_LIB standard
J 0
(-5750 5675);
DISPLAY INVISIBLE (-5750 5675);
FORCEPROP 1 LAST OFFPAGE TRUE
J 2
(-6075 5550);
DISPLAY 0.872340 (-6075 5550);
PAINT GREEN (-6075 5550);
DISPLAY INVISIBLE (-6075 5550);
FORCEPROP 1 LAST COMMENT_BODY TRUE
J 2
(-5725 5575);
DISPLAY 0.872340 (-5725 5575);
PAINT GREEN (-5725 5575);
DISPLAY INVISIBLE (-5725 5575);
FORCEPROP 2 LAST PATH I69
J 0
(-5700 5750);
DISPLAY 1.021277 (-5700 5750);
DISPLAY INVISIBLE (-5700 5750);
FORCEADD OFFPAGE..4
R 2
(-5750 5625);
FORCEPROP 2 LAST $XR1 82 
J 0
(-6061 5625);
DISPLAY 0.638298 (-6061 5625);
PAINT MONO (-6061 5625);
FORCEPROP 2 LAST $XR0 80 
J 0
(-5971 5625);
DISPLAY 0.638298 (-5971 5625);
PAINT MONO (-5971 5625);
FORCEPROP 2 LAST CDS_LIB standard
J 0
(-5750 5625);
DISPLAY INVISIBLE (-5750 5625);
FORCEPROP 1 LAST OFFPAGE TRUE
J 2
(-6075 5500);
DISPLAY 0.872340 (-6075 5500);
PAINT GREEN (-6075 5500);
DISPLAY INVISIBLE (-6075 5500);
FORCEPROP 1 LAST COMMENT_BODY TRUE
J 2
(-5725 5525);
DISPLAY 0.872340 (-5725 5525);
PAINT GREEN (-5725 5525);
DISPLAY INVISIBLE (-5725 5525);
FORCEPROP 2 LAST PATH I70
J 0
(-5700 5700);
DISPLAY 1.021277 (-5700 5700);
DISPLAY INVISIBLE (-5700 5700);
FORCEADD OFFPAGE..2
R 2
(-6125 3075);
FORCEPROP 2 LAST $XR0 144 
J 0
(-6380 3075);
DISPLAY 0.638298 (-6380 3075);
PAINT MONO (-6380 3075);
FORCEPROP 2 LAST CDS_LIB standard
J 0
(-6125 3075);
DISPLAY INVISIBLE (-6125 3075);
FORCEPROP 1 LAST OFFPAGE TRUE
J 2
(-6450 2950);
DISPLAY 0.872340 (-6450 2950);
PAINT GREEN (-6450 2950);
DISPLAY INVISIBLE (-6450 2950);
FORCEPROP 1 LAST COMMENT_BODY TRUE
J 2
(-6080 2980);
DISPLAY 0.872340 (-6080 2980);
PAINT GREEN (-6080 2980);
DISPLAY INVISIBLE (-6080 2980);
FORCEPROP 2 LAST PATH I71
J 0
(-6375 3125);
DISPLAY 1.021277 (-6375 3125);
DISPLAY INVISIBLE (-6375 3125);
FORCEADD OFFPAGE..2
R 2
(-6125 2525);
FORCEPROP 2 LAST $XR1 81 
J 0
(-6439 2525);
DISPLAY 0.638298 (-6439 2525);
PAINT MONO (-6439 2525);
FORCEPROP 2 LAST $XR0 27 
J 0
(-6349 2525);
DISPLAY 0.638298 (-6349 2525);
PAINT MONO (-6349 2525);
FORCEPROP 2 LAST CDS_LIB standard
J 0
(-6125 2525);
DISPLAY INVISIBLE (-6125 2525);
FORCEPROP 1 LAST OFFPAGE TRUE
J 2
(-6450 2400);
DISPLAY 0.872340 (-6450 2400);
PAINT GREEN (-6450 2400);
DISPLAY INVISIBLE (-6450 2400);
FORCEPROP 1 LAST COMMENT_BODY TRUE
J 2
(-6080 2430);
DISPLAY 0.872340 (-6080 2430);
PAINT GREEN (-6080 2430);
DISPLAY INVISIBLE (-6080 2430);
FORCEPROP 2 LAST PATH I72
J 0
(-6375 2575);
DISPLAY 1.021277 (-6375 2575);
DISPLAY INVISIBLE (-6375 2575);
FORCEADD OFFPAGE..2
R 2
(-6125 2475);
FORCEPROP 2 LAST $XR1 81 
J 0
(-6439 2475);
DISPLAY 0.638298 (-6439 2475);
PAINT MONO (-6439 2475);
FORCEPROP 2 LAST $XR0 27 
J 0
(-6349 2475);
DISPLAY 0.638298 (-6349 2475);
PAINT MONO (-6349 2475);
FORCEPROP 2 LAST CDS_LIB standard
J 0
(-6125 2475);
DISPLAY INVISIBLE (-6125 2475);
FORCEPROP 1 LAST OFFPAGE TRUE
J 2
(-6450 2350);
DISPLAY 0.872340 (-6450 2350);
PAINT GREEN (-6450 2350);
DISPLAY INVISIBLE (-6450 2350);
FORCEPROP 1 LAST COMMENT_BODY TRUE
J 2
(-6080 2380);
DISPLAY 0.872340 (-6080 2380);
PAINT GREEN (-6080 2380);
DISPLAY INVISIBLE (-6080 2380);
FORCEPROP 2 LAST PATH I73
J 0
(-6375 2525);
DISPLAY 1.021277 (-6375 2525);
DISPLAY INVISIBLE (-6375 2525);
FORCEADD OFFPAGE..2
(-7725 3100);
FORCEPROP 2 LAST $XR1 81 
J 0
(-7446 3100);
DISPLAY 0.638298 (-7446 3100);
PAINT MONO (-7446 3100);
FORCEPROP 2 LAST $XR0 27 
J 0
(-7536 3100);
DISPLAY 0.638298 (-7536 3100);
PAINT MONO (-7536 3100);
FORCEPROP 2 LAST CDS_LIB standard
J 0
(-7725 3100);
DISPLAY INVISIBLE (-7725 3100);
FORCEPROP 1 LAST OFFPAGE TRUE
J 0
(-7400 2975);
DISPLAY 0.872340 (-7400 2975);
PAINT GREEN (-7400 2975);
DISPLAY INVISIBLE (-7400 2975);
FORCEPROP 1 LAST COMMENT_BODY TRUE
J 0
(-7770 3005);
DISPLAY 0.872340 (-7770 3005);
PAINT PEACH (-7770 3005);
DISPLAY INVISIBLE (-7770 3005);
FORCEPROP 2 LAST PATH I74
J 2
(-7525 3150);
DISPLAY 1.021277 (-7525 3150);
DISPLAY INVISIBLE (-7525 3150);
FORCEADD OFFPAGE..2
(-7725 3150);
FORCEPROP 2 LAST $XR1 81 
J 0
(-7446 3150);
DISPLAY 0.638298 (-7446 3150);
PAINT MONO (-7446 3150);
FORCEPROP 2 LAST $XR0 27 
J 0
(-7536 3150);
DISPLAY 0.638298 (-7536 3150);
PAINT MONO (-7536 3150);
FORCEPROP 2 LAST CDS_LIB standard
J 0
(-7725 3150);
DISPLAY INVISIBLE (-7725 3150);
FORCEPROP 1 LAST OFFPAGE TRUE
J 0
(-7400 3025);
DISPLAY 0.872340 (-7400 3025);
PAINT GREEN (-7400 3025);
DISPLAY INVISIBLE (-7400 3025);
FORCEPROP 1 LAST COMMENT_BODY TRUE
J 0
(-7770 3055);
DISPLAY 0.872340 (-7770 3055);
PAINT PEACH (-7770 3055);
DISPLAY INVISIBLE (-7770 3055);
FORCEPROP 2 LAST PATH I75
J 2
(-7525 3200);
DISPLAY 1.021277 (-7525 3200);
DISPLAY INVISIBLE (-7525 3200);
FORCEADD OFFPAGE..2
R 2
(-6125 2775);
FORCEPROP 2 LAST $XR1 81 
J 0
(-6439 2775);
DISPLAY 0.638298 (-6439 2775);
PAINT MONO (-6439 2775);
FORCEPROP 2 LAST $XR0 27 
J 0
(-6349 2775);
DISPLAY 0.638298 (-6349 2775);
PAINT MONO (-6349 2775);
FORCEPROP 2 LAST CDS_LIB standard
J 0
(-6125 2775);
DISPLAY INVISIBLE (-6125 2775);
FORCEPROP 1 LAST OFFPAGE TRUE
J 2
(-6450 2650);
DISPLAY 0.872340 (-6450 2650);
PAINT GREEN (-6450 2650);
DISPLAY INVISIBLE (-6450 2650);
FORCEPROP 1 LAST COMMENT_BODY TRUE
J 2
(-6080 2680);
DISPLAY 0.872340 (-6080 2680);
PAINT GREEN (-6080 2680);
DISPLAY INVISIBLE (-6080 2680);
FORCEPROP 2 LAST PATH I79
J 0
(-6375 2825);
DISPLAY 1.021277 (-6375 2825);
DISPLAY INVISIBLE (-6375 2825);
FORCEADD OFFPAGE..2
R 2
(-6125 2725);
FORCEPROP 2 LAST $XR1 81 
J 0
(-6439 2725);
DISPLAY 0.638298 (-6439 2725);
PAINT MONO (-6439 2725);
FORCEPROP 2 LAST $XR0 27 
J 0
(-6349 2725);
DISPLAY 0.638298 (-6349 2725);
PAINT MONO (-6349 2725);
FORCEPROP 2 LAST CDS_LIB standard
J 0
(-6125 2725);
DISPLAY INVISIBLE (-6125 2725);
FORCEPROP 1 LAST OFFPAGE TRUE
J 2
(-6450 2600);
DISPLAY 0.872340 (-6450 2600);
PAINT GREEN (-6450 2600);
DISPLAY INVISIBLE (-6450 2600);
FORCEPROP 1 LAST COMMENT_BODY TRUE
J 2
(-6080 2630);
DISPLAY 0.872340 (-6080 2630);
PAINT GREEN (-6080 2630);
DISPLAY INVISIBLE (-6080 2630);
FORCEPROP 2 LAST PATH I80
J 0
(-6375 2775);
DISPLAY 1.021277 (-6375 2775);
DISPLAY INVISIBLE (-6375 2775);
FORCEADD OFFPAGE..2
R 2
(-6125 2675);
FORCEPROP 2 LAST $XR1 81 
J 0
(-6439 2675);
DISPLAY 0.638298 (-6439 2675);
PAINT MONO (-6439 2675);
FORCEPROP 2 LAST $XR0 27 
J 0
(-6349 2675);
DISPLAY 0.638298 (-6349 2675);
PAINT MONO (-6349 2675);
FORCEPROP 2 LAST CDS_LIB standard
J 0
(-6125 2675);
DISPLAY INVISIBLE (-6125 2675);
FORCEPROP 1 LAST OFFPAGE TRUE
J 2
(-6450 2550);
DISPLAY 0.872340 (-6450 2550);
PAINT GREEN (-6450 2550);
DISPLAY INVISIBLE (-6450 2550);
FORCEPROP 1 LAST COMMENT_BODY TRUE
J 2
(-6080 2580);
DISPLAY 0.872340 (-6080 2580);
PAINT GREEN (-6080 2580);
DISPLAY INVISIBLE (-6080 2580);
FORCEPROP 2 LAST PATH I81
J 0
(-6375 2725);
DISPLAY 1.021277 (-6375 2725);
DISPLAY INVISIBLE (-6375 2725);
FORCEADD OFFPAGE..2
R 2
(-6125 2625);
FORCEPROP 2 LAST $XR1 81 
J 0
(-6439 2625);
DISPLAY 0.638298 (-6439 2625);
PAINT MONO (-6439 2625);
FORCEPROP 2 LAST $XR0 27 
J 0
(-6349 2625);
DISPLAY 0.638298 (-6349 2625);
PAINT MONO (-6349 2625);
FORCEPROP 2 LAST CDS_LIB standard
J 0
(-6125 2625);
DISPLAY INVISIBLE (-6125 2625);
FORCEPROP 1 LAST OFFPAGE TRUE
J 2
(-6450 2500);
DISPLAY 0.872340 (-6450 2500);
PAINT GREEN (-6450 2500);
DISPLAY INVISIBLE (-6450 2500);
FORCEPROP 1 LAST COMMENT_BODY TRUE
J 2
(-6080 2530);
DISPLAY 0.872340 (-6080 2530);
PAINT GREEN (-6080 2530);
DISPLAY INVISIBLE (-6080 2530);
FORCEPROP 2 LAST PATH I82
J 0
(-6375 2675);
DISPLAY 1.021277 (-6375 2675);
DISPLAY INVISIBLE (-6375 2675);
FORCEADD OFFPAGE..2
(-7725 3050);
FORCEPROP 2 LAST $XR1 81 
J 0
(-7446 3050);
DISPLAY 0.638298 (-7446 3050);
PAINT MONO (-7446 3050);
FORCEPROP 2 LAST $XR0 27 
J 0
(-7536 3050);
DISPLAY 0.638298 (-7536 3050);
PAINT MONO (-7536 3050);
FORCEPROP 2 LAST CDS_LIB standard
J 0
(-7725 3050);
DISPLAY INVISIBLE (-7725 3050);
FORCEPROP 1 LAST OFFPAGE TRUE
J 0
(-7400 2925);
DISPLAY 0.872340 (-7400 2925);
PAINT GREEN (-7400 2925);
DISPLAY INVISIBLE (-7400 2925);
FORCEPROP 1 LAST COMMENT_BODY TRUE
J 0
(-7770 2955);
DISPLAY 0.872340 (-7770 2955);
PAINT PEACH (-7770 2955);
DISPLAY INVISIBLE (-7770 2955);
FORCEPROP 2 LAST PATH I85
J 0
(-7550 3125);
DISPLAY 1.021277 (-7550 3125);
DISPLAY INVISIBLE (-7550 3125);
FORCEADD OFFPAGE..2
(-7725 3000);
FORCEPROP 2 LAST $XR1 81 
J 0
(-7446 3000);
DISPLAY 0.638298 (-7446 3000);
PAINT MONO (-7446 3000);
FORCEPROP 2 LAST $XR0 27 
J 0
(-7536 3000);
DISPLAY 0.638298 (-7536 3000);
PAINT MONO (-7536 3000);
FORCEPROP 2 LAST CDS_LIB standard
J 0
(-7725 3000);
DISPLAY INVISIBLE (-7725 3000);
FORCEPROP 1 LAST OFFPAGE TRUE
J 0
(-7400 2875);
DISPLAY 0.872340 (-7400 2875);
PAINT GREEN (-7400 2875);
DISPLAY INVISIBLE (-7400 2875);
FORCEPROP 1 LAST COMMENT_BODY TRUE
J 0
(-7770 2905);
DISPLAY 0.872340 (-7770 2905);
PAINT PEACH (-7770 2905);
DISPLAY INVISIBLE (-7770 2905);
FORCEPROP 2 LAST PATH I86
J 0
(-7550 3075);
DISPLAY 1.021277 (-7550 3075);
DISPLAY INVISIBLE (-7550 3075);
FORCEADD OFFPAGE..2
(-7775 4525);
FORCEPROP 2 LAST $XR1 27 
J 0
(-7496 4525);
DISPLAY 0.638298 (-7496 4525);
PAINT MONO (-7496 4525);
FORCEPROP 2 LAST $XR0 81 
J 0
(-7586 4525);
DISPLAY 0.638298 (-7586 4525);
PAINT MONO (-7586 4525);
FORCEPROP 2 LAST CDS_LIB standard
J 0
(-7775 4525);
DISPLAY INVISIBLE (-7775 4525);
FORCEPROP 1 LAST OFFPAGE TRUE
J 0
(-7450 4400);
DISPLAY 0.872340 (-7450 4400);
PAINT GREEN (-7450 4400);
DISPLAY INVISIBLE (-7450 4400);
FORCEPROP 1 LAST COMMENT_BODY TRUE
J 0
(-7820 4430);
DISPLAY 0.872340 (-7820 4430);
PAINT PEACH (-7820 4430);
DISPLAY INVISIBLE (-7820 4430);
FORCEPROP 2 LAST PATH I87
J 0
(-7575 4575);
DISPLAY 1.021277 (-7575 4575);
DISPLAY INVISIBLE (-7575 4575);
FORCEADD OFFPAGE..2
(-7775 4475);
FORCEPROP 2 LAST $XR1 27 
J 0
(-7496 4475);
DISPLAY 0.638298 (-7496 4475);
PAINT MONO (-7496 4475);
FORCEPROP 2 LAST $XR0 81 
J 0
(-7586 4475);
DISPLAY 0.638298 (-7586 4475);
PAINT MONO (-7586 4475);
FORCEPROP 2 LAST CDS_LIB standard
J 0
(-7775 4475);
DISPLAY INVISIBLE (-7775 4475);
FORCEPROP 1 LAST OFFPAGE TRUE
J 0
(-7450 4350);
DISPLAY 0.872340 (-7450 4350);
PAINT GREEN (-7450 4350);
DISPLAY INVISIBLE (-7450 4350);
FORCEPROP 1 LAST COMMENT_BODY TRUE
J 0
(-7820 4380);
DISPLAY 0.872340 (-7820 4380);
PAINT PEACH (-7820 4380);
DISPLAY INVISIBLE (-7820 4380);
FORCEPROP 2 LAST PATH I88
J 0
(-7575 4525);
DISPLAY 1.021277 (-7575 4525);
DISPLAY INVISIBLE (-7575 4525);
FORCEADD OFFPAGE..4
R 2
(-6125 2975);
FORCEPROP 2 LAST $XR1 81 
J 0
(-6466 2975);
DISPLAY 0.638298 (-6466 2975);
PAINT MONO (-6466 2975);
FORCEPROP 2 LAST $XR0 27 
J 0
(-6376 2975);
DISPLAY 0.638298 (-6376 2975);
PAINT MONO (-6376 2975);
FORCEPROP 2 LAST CDS_LIB standard
J 0
(-6125 2975);
DISPLAY INVISIBLE (-6125 2975);
FORCEPROP 1 LAST OFFPAGE TRUE
J 2
(-6450 2850);
DISPLAY 0.872340 (-6450 2850);
PAINT GREEN (-6450 2850);
DISPLAY INVISIBLE (-6450 2850);
FORCEPROP 1 LAST COMMENT_BODY TRUE
J 2
(-6100 2875);
DISPLAY 0.872340 (-6100 2875);
PAINT GREEN (-6100 2875);
DISPLAY INVISIBLE (-6100 2875);
FORCEPROP 2 LAST PATH I92
J 0
(-6375 3025);
DISPLAY 1.021277 (-6375 3025);
DISPLAY INVISIBLE (-6375 3025);
FORCEADD OFFPAGE..4
R 2
(-6125 2925);
FORCEPROP 2 LAST $XR1 81 
J 0
(-6466 2925);
DISPLAY 0.638298 (-6466 2925);
PAINT MONO (-6466 2925);
FORCEPROP 2 LAST $XR0 27 
J 0
(-6376 2925);
DISPLAY 0.638298 (-6376 2925);
PAINT MONO (-6376 2925);
FORCEPROP 2 LAST CDS_LIB standard
J 0
(-6125 2925);
DISPLAY INVISIBLE (-6125 2925);
FORCEPROP 1 LAST OFFPAGE TRUE
J 2
(-6450 2800);
DISPLAY 0.872340 (-6450 2800);
PAINT GREEN (-6450 2800);
DISPLAY INVISIBLE (-6450 2800);
FORCEPROP 1 LAST COMMENT_BODY TRUE
J 2
(-6100 2825);
DISPLAY 0.872340 (-6100 2825);
PAINT GREEN (-6100 2825);
DISPLAY INVISIBLE (-6100 2825);
FORCEPROP 2 LAST PATH I93
J 0
(-6375 2975);
DISPLAY 1.021277 (-6375 2975);
DISPLAY INVISIBLE (-6375 2975);
FORCEADD GND..1
(-8550 4150);
FORCEPROP 3 LASTPIN (-8550 4200) SIG_NAME GND\g
J 0
(-8540 4210);
DISPLAY 0.659574 (-8540 4210);
PAINT MONO (-8540 4210);
DISPLAY INVISIBLE (-8540 4210);
FORCEPROP 2 LAST CDS_LIB pure_quanta_power
J 0
(-8550 4150);
DISPLAY INVISIBLE (-8550 4150);
FORCEPROP 1 LAST SIZE 1B
J 0
(-8475 4100);
DISPLAY 0.872340 (-8475 4100);
PAINT GREEN (-8475 4100);
DISPLAY INVISIBLE (-8475 4100);
FORCEPROP 1 LAST PATH I95
J 0
(-8475 4150);
DISPLAY 0.872340 (-8475 4150);
PAINT AQUA (-8475 4150);
DISPLAY INVISIBLE (-8475 4150);
FORCEPROP 1 LAST HDL_POWER GND
J 0
(-8550 4300);
DISPLAY 0.872340 (-8550 4300);
PAINT GREEN (-8550 4300);
DISPLAY INVISIBLE (-8550 4300);
FORCEADD GND..1
(-8675 4150);
FORCEPROP 3 LASTPIN (-8675 4200) SIG_NAME GND\g
J 0
(-8665 4210);
DISPLAY 0.659574 (-8665 4210);
PAINT MONO (-8665 4210);
DISPLAY INVISIBLE (-8665 4210);
FORCEPROP 2 LAST CDS_LIB pure_quanta_power
J 0
(-8675 4150);
DISPLAY INVISIBLE (-8675 4150);
FORCEPROP 1 LAST SIZE 1B
J 0
(-8600 4100);
DISPLAY 0.872340 (-8600 4100);
PAINT GREEN (-8600 4100);
DISPLAY INVISIBLE (-8600 4100);
FORCEPROP 1 LAST PATH I96
J 0
(-8600 4150);
DISPLAY 0.872340 (-8600 4150);
PAINT AQUA (-8600 4150);
DISPLAY INVISIBLE (-8600 4150);
FORCEPROP 1 LAST HDL_POWER GND
J 0
(-8675 4300);
DISPLAY 0.872340 (-8675 4300);
PAINT GREEN (-8675 4300);
DISPLAY INVISIBLE (-8675 4300);
FORCEADD DNS..2
(-7050 575);
PAINT RED (-7050 575);
FORCEPROP 2 LAST CDS_LIB mstr_misc
J 0
(-7050 575);
DISPLAY INVISIBLE (-7050 575);
FORCEPROP 1 LAST COMMENT_BODY TRUE
J 0
(-7050 575);
PAINT RED (-7050 575);
DISPLAY INVISIBLE (-7050 575);
FORCEADD DNS..2
(-8650 4650);
PAINT RED (-8650 4650);
FORCEPROP 2 LAST CDS_LIB mstr_misc
J 0
(-8650 4650);
DISPLAY INVISIBLE (-8650 4650);
FORCEPROP 1 LAST COMMENT_BODY TRUE
J 0
(-8650 4650);
PAINT RED (-8650 4650);
DISPLAY INVISIBLE (-8650 4650);
FORCEADD DNS..2
(-8025 575);
PAINT RED (-8025 575);
FORCEPROP 2 LAST CDS_LIB mstr_misc
J 0
(-8025 575);
PAINT MONO (-8025 575);
DISPLAY INVISIBLE (-8025 575);
FORCEPROP 1 LAST COMMENT_BODY TRUE
J 0
(-8025 575);
PAINT RED (-8025 575);
DISPLAY INVISIBLE (-8025 575);
FORCEADD DNS..2
(-7700 575);
PAINT RED (-7700 575);
FORCEPROP 2 LAST CDS_LIB mstr_misc
J 0
(-7700 575);
DISPLAY INVISIBLE (-7700 575);
FORCEPROP 1 LAST COMMENT_BODY TRUE
J 0
(-7700 575);
PAINT RED (-7700 575);
DISPLAY INVISIBLE (-7700 575);
FORCEADD QUANTA_TITLE_BLOCK_C..1
(0 0);
FORCEPROP 0 LAST CDS_CON_LAST_MODIFIED Fri Mar 11 14:52:21 2022
J 0
(-1885 15);
DISPLAY INVISIBLE (-1885 15);
FORCEPROP 1 LAST CUSTOM_TXT_CDS <CON_LAST_MODIFIED>
J 0
(-1885 15);
DISPLAY 0.978723 (-1885 15);
FORCEPROP 2 LAST CUSTOM_TXT_CDS <XR_PAGE_TITLE>
J 0
(-7890 5250);
DISPLAY 0.638298 (-7890 5250);
PAINT PINK (-7890 5250);
DISPLAY INVISIBLE (-7890 5250);
FORCEPROP 1 LAST CUSTOM_TXT_CDS <NAME_2>
J 0
(-3175 50);
FORCEPROP 1 LAST CUSTOM_TXT_CDS <NAME_1>
J 0
(-3175 175);
FORCEPROP 1 LAST CUSTOM_TXT_CDS <Q_NUMBER>
J 0
(-1403 103);
DISPLAY 1.212766 (-1403 103);
FORCEPROP 1 LAST CUSTOM_TXT_CDS <Q_PROJ>
J 0
(-2382 102);
DISPLAY 1.212766 (-2382 102);
FORCEPROP 1 LAST CUSTOM_TXT_CDS <Q_REV>
J 0
(-184 103);
DISPLAY 1.212766 (-184 103);
FORCEPROP 1 LAST CUSTOM_TXT_CDS <CON_PAGE_NUM> OF <CON_TOTAL_PAGES>
J 0
(-446 18);
DISPLAY 0.978723 (-446 18);
FORCEPROP 1 LAST Q_DEPT BU9
J 1
(-3763 49);
DISPLAY 1.957447 (-3763 49);
PAINT GREEN (-3763 49);
FORCEPROP 1 LAST Q_TITLE CPU0 MISC 1/2
J 0
(-9275 75);
DISPLAY 2.446809 (-9275 75);
PAINT GREEN (-9275 75);
FORCEPROP 2 LAST PAGE_BORDER TRUE
J 0
(-7890 5250);
DISPLAY 0.638298 (-7890 5250);
PAINT PINK (-7890 5250);
DISPLAY INVISIBLE (-7890 5250);
FORCEPROP 1 LAST CDS_LMAN_SYM_OUTLINE -9475,6775,100,-125
J 0
(0 0);
DISPLAY 0.468085 (0 0);
PAINT GREEN (0 0);
DISPLAY INVISIBLE (0 0);
FORCEPROP 2 LAST CDS_LIB pure_quanta
J 0
(0 0);
DISPLAY INVISIBLE (0 0);
FORCEPROP 1 LAST COMMENT_BODY TRUE
J 0
(12 -13);
DISPLAY 0.978723 (12 -13);
PAINT GREEN (12 -13);
DISPLAY INVISIBLE (12 -13);
FORCEPROP 2 LAST CDS_XR_PAGE_TITLE CR-27 : @T6G_MB_LIB.T6G(SCH_1):PAGE27
J 0
(-7890 5250);
DISPLAY 0.638298 (-7890 5250);
PAINT PINK (-7890 5250);
DISPLAY INVISIBLE (-7890 5250);
FORCEADD DNS..2
(-6400 575);
PAINT RED (-6400 575);
FORCEPROP 2 LAST CDS_LIB mstr_misc
J 0
(-6400 575);
DISPLAY INVISIBLE (-6400 575);
FORCEPROP 1 LAST COMMENT_BODY TRUE
J 0
(-6400 575);
PAINT RED (-6400 575);
DISPLAY INVISIBLE (-6400 575);
FORCEADD DNS..2
(-6675 575);
PAINT RED (-6675 575);
FORCEPROP 2 LAST CDS_LIB mstr_misc
J 0
(-6675 575);
DISPLAY INVISIBLE (-6675 575);
FORCEPROP 1 LAST COMMENT_BODY TRUE
J 0
(-6675 575);
PAINT RED (-6675 575);
DISPLAY INVISIBLE (-6675 575);
FORCEADD DNS..2
(-7375 575);
PAINT RED (-7375 575);
FORCEPROP 2 LAST CDS_LIB mstr_misc
J 0
(-7375 575);
DISPLAY INVISIBLE (-7375 575);
FORCEPROP 1 LAST COMMENT_BODY TRUE
J 0
(-7375 575);
PAINT RED (-7375 575);
DISPLAY INVISIBLE (-7375 575);
WIRE 16 -1 (-8675 4750)(-8675 4775);
WIRE 16 -1 (-6375 500)(-6375 350);
WIRE 16 -1 (-6675 500)(-6675 350);
WIRE 16 -1 (-5025 1125)(-5250 1125);
WIRE 16 -1 (-5250 1125)(-5250 1025);
WIRE 16 -1 (-7350 500)(-7350 350);
WIRE 16 -1 (-7025 500)(-7025 350);
WIRE 16 -1 (-8000 500)(-8000 350);
WIRE 16 -1 (-7675 500)(-7675 350);
WIRE 16 -1 (-8550 4250)(-8550 4200);
WIRE 16 -1 (-8675 4250)(-8675 4200);
WIRE 16 -1 (-3525 4175)(-2700 4175);
FORCEPROP 2 LAST SIG_NAME CPU0_BP1
J 0
(-3310 4185);
DISPLAY 0.489362 (-3310 4185);
WIRE 16 -1 (-3525 4125)(-2700 4125);
FORCEPROP 2 LAST SIG_NAME CPU0_BP2
J 0
(-3310 4135);
DISPLAY 0.489362 (-3310 4135);
WIRE 16 -1 (-3525 4075)(-2700 4075);
FORCEPROP 2 LAST SIG_NAME CPU0_BP3
J 0
(-3310 4085);
DISPLAY 0.489362 (-3310 4085);
WIRE 16 -1 (-3525 3875)(-2750 3875);
FORCEPROP 2 LAST SIG_NAME TP_CPU0_TEST6_CCD0
J 0
(-3290 3885);
DISPLAY 0.489362 (-3290 3885);
FORCEPROP 2 LASTPROP $XRERR UNIQUE?
J 0
(-2720 3875);
DISPLAY 0.638298 (-2720 3875);
PAINT MONO (-2720 3875);
DISPLAY INVISIBLE (-2720 3875);
WIRE 16 -1 (-3525 3825)(-2750 3825);
FORCEPROP 2 LAST SIG_NAME TP_CPU0_TEST6_CCD1
J 0
(-3290 3835);
DISPLAY 0.489362 (-3290 3835);
FORCEPROP 2 LASTPROP $XRERR UNIQUE?
J 0
(-2720 3825);
DISPLAY 0.638298 (-2720 3825);
PAINT MONO (-2720 3825);
DISPLAY INVISIBLE (-2720 3825);
WIRE 16 -1 (-1375 2800)(-775 2800);
FORCEPROP 2 LAST SIG_NAME CPU0_XTRIG_R1_L7
J 0
(-1235 2810);
DISPLAY 0.489362 (-1235 2810);
FORCEPROP 2 LASTPROP $XRERR UNIQUE?
J 0
(-1475 2810);
DISPLAY 0.638298 (-1475 2810);
PAINT MONO (-1475 2810);
DISPLAY INVISIBLE (-1475 2810);
WIRE 16 -1 (-3525 3775)(-2750 3775);
FORCEPROP 2 LAST SIG_NAME TP_CPU0_TEST6_CCD2
J 0
(-3290 3785);
DISPLAY 0.489362 (-3290 3785);
FORCEPROP 2 LASTPROP $XRERR UNIQUE?
J 0
(-2720 3775);
DISPLAY 0.638298 (-2720 3775);
PAINT MONO (-2720 3775);
DISPLAY INVISIBLE (-2720 3775);
WIRE 16 -1 (-2625 4425)(-2025 4425);
FORCEPROP 2 LAST SIG_NAME CPU0_XTRIG_L7
J 0
(-2425 4435);
DISPLAY 0.489362 (-2425 4435);
WIRE 16 -1 (-2625 4475)(-2025 4475);
FORCEPROP 2 LAST SIG_NAME CPU0_XTRIG_L6
J 0
(-2425 4485);
DISPLAY 0.489362 (-2425 4485);
WIRE 16 -1 (-2625 4525)(-2025 4525);
FORCEPROP 2 LAST SIG_NAME CPU0_XTRIG_L5
J 0
(-2425 4535);
DISPLAY 0.489362 (-2425 4535);
WIRE 16 -1 (-2625 4575)(-2025 4575);
FORCEPROP 2 LAST SIG_NAME CPU0_XTRIG_L4
J 0
(-2425 4585);
DISPLAY 0.489362 (-2425 4585);
WIRE 16 -1 (-3525 4225)(-2700 4225);
FORCEPROP 2 LAST SIG_NAME CPU0_BP0
J 0
(-3310 4235);
DISPLAY 0.489362 (-3310 4235);
WIRE 16 -1 (-1650 3825)(-1150 3825);
FORCEPROP 2 LAST SIG_NAME CPU0_THERMTRIP_R_N
J 0
(-1785 3910);
DISPLAY 0.553191 (-1785 3910);
WIRE 16 -1 (-675 5400)(-1475 5400);
FORCEPROP 2 LAST SIG_NAME CPU0_PROCHOT_N
J 0
(-1450 5410);
DISPLAY 0.489362 (-1450 5410);
WIRE 16 -1 (-950 3825)(-475 3825);
FORCEPROP 2 LAST SIG_NAME CPU1_THERMTRIP_R_N
J 0
(-810 3910);
DISPLAY 0.553191 (-810 3910);
WIRE 16 -1 (-3525 3725)(-2750 3725);
FORCEPROP 2 LAST SIG_NAME TP_CPU0_TEST6_CCD3
J 0
(-3290 3735);
DISPLAY 0.489362 (-3290 3735);
FORCEPROP 2 LASTPROP $XRERR UNIQUE?
J 0
(-2720 3725);
DISPLAY 0.638298 (-2720 3725);
PAINT MONO (-2720 3725);
DISPLAY INVISIBLE (-2720 3725);
WIRE 16 -1 (-6075 4425)(-5025 4425);
FORCEPROP 2 LAST SIG_NAME JTAG_CPU0_TCK
J 0
(-5910 4435);
DISPLAY 0.489362 (-5910 4435);
WIRE 16 -1 (-475 5600)(-225 5600);
WIRE 16 -1 (-225 5875)(-225 5600);
WIRE 16 -1 (-225 5550)(-225 5600);
WIRE 16 -1 (-475 5550)(-225 5550);
WIRE 16 -1 (-225 5500)(-225 5550);
WIRE 16 -1 (-475 5500)(-225 5500);
WIRE 16 -1 (-225 5450)(-225 5500);
WIRE 16 -1 (-475 5450)(-225 5450);
WIRE 16 -1 (-225 5400)(-225 5450);
WIRE 16 -1 (-475 5400)(-225 5400);
WIRE 16 -1 (-225 5350)(-225 5400);
WIRE 16 -1 (-475 5350)(-225 5350);
WIRE 16 -1 (-225 5300)(-225 5350);
WIRE 16 -1 (-475 5300)(-225 5300);
WIRE 16 -1 (-225 5250)(-225 5300);
WIRE 16 -1 (-475 5250)(-225 5250);
WIRE 16 -1 (-225 5200)(-225 5250);
WIRE 16 -1 (-475 5200)(-225 5200);
WIRE 16 -1 (-225 5150)(-225 5200);
WIRE 16 -1 (-475 5150)(-225 5150);
WIRE 16 -1 (-225 5100)(-225 5150);
WIRE 16 -1 (-475 5100)(-225 5100);
WIRE 16 -1 (-8000 1475)(-7675 1475);
WIRE 16 -1 (-8000 1525)(-8000 1475);
WIRE 16 -1 (-8000 1475)(-8000 1400);
WIRE 16 -1 (-7675 1475)(-7350 1475);
WIRE 16 -1 (-7675 1400)(-7675 1475);
WIRE 16 -1 (-7350 1475)(-7025 1475);
WIRE 16 -1 (-7350 1400)(-7350 1475);
WIRE 16 -1 (-7025 1475)(-6675 1475);
WIRE 16 -1 (-7025 1400)(-7025 1475);
WIRE 16 -1 (-6675 1475)(-6375 1475);
WIRE 16 -1 (-6675 1475)(-6675 1400);
WIRE 16 -1 (-6375 1475)(-6375 1400);
WIRE 16 -1 (-150 2850)(-150 2800);
WIRE 16 -1 (-150 2900)(-150 2850);
WIRE 16 -1 (-225 2850)(-150 2850);
WIRE 16 -1 (-225 2800)(-150 2800);
WIRE 16 -1 (-150 2800)(-150 2700);
WIRE 16 -1 (-225 2900)(-150 2900);
WIRE 16 -1 (-150 2950)(-150 2900);
WIRE 16 -1 (-225 2950)(-150 2950);
WIRE 16 -1 (-150 2225)(-150 2175);
WIRE 16 -1 (-150 2275)(-150 2225);
WIRE 16 -1 (-225 2225)(-150 2225);
WIRE 16 -1 (-150 2175)(-150 2075);
WIRE 16 -1 (-225 2175)(-150 2175);
WIRE 16 -1 (-225 2275)(-150 2275);
WIRE 16 -1 (-150 2325)(-150 2275);
WIRE 16 -1 (-225 2325)(-150 2325);
WIRE 16 -1 (-9050 3350)(-9050 3150);
WIRE 16 -1 (-8800 3150)(-9050 3150);
WIRE 16 -1 (-9050 3100)(-9050 3150);
WIRE 16 -1 (-8800 3100)(-9050 3100);
WIRE 16 -1 (-9050 3050)(-9050 3100);
WIRE 16 -1 (-8800 3050)(-9050 3050);
WIRE 16 -1 (-9050 3000)(-9050 3050);
WIRE 16 -1 (-8800 3000)(-9050 3000);
WIRE 16 -1 (-9050 2950)(-9050 3000);
WIRE 16 -1 (-8800 2950)(-9050 2950);
WIRE 16 -1 (-9050 2900)(-9050 2950);
WIRE 16 -1 (-8800 2900)(-9050 2900);
WIRE 16 -1 (-9050 2850)(-9050 2900);
WIRE 16 -1 (-8800 2850)(-9050 2850);
WIRE 16 -1 (-3525 4575)(-2825 4575);
FORCEPROP 2 LAST SIG_NAME CPU0_XTRIG_R2_L4
J 0
(-3325 4585);
DISPLAY 0.489362 (-3325 4585);
FORCEPROP 2 LASTPROP $XRERR UNIQUE?
J 0
(-3565 4585);
DISPLAY 0.638298 (-3565 4585);
PAINT MONO (-3565 4585);
DISPLAY INVISIBLE (-3565 4585);
WIRE 16 -1 (-3525 4525)(-2825 4525);
FORCEPROP 2 LAST SIG_NAME CPU0_XTRIG_R2_L5
J 0
(-3325 4535);
DISPLAY 0.489362 (-3325 4535);
FORCEPROP 2 LASTPROP $XRERR UNIQUE?
J 0
(-3565 4535);
DISPLAY 0.638298 (-3565 4535);
PAINT MONO (-3565 4535);
DISPLAY INVISIBLE (-3565 4535);
WIRE 16 -1 (-2625 4875)(-2025 4875);
FORCEPROP 2 LAST SIG_NAME APML_CPU0_ALERT_R_N
J 0
(-2475 4885);
DISPLAY 0.489362 (-2475 4885);
WIRE 16 -1 (-3525 4475)(-2825 4475);
FORCEPROP 2 LAST SIG_NAME CPU0_XTRIG_R2_L6
J 0
(-3325 4485);
DISPLAY 0.489362 (-3325 4485);
FORCEPROP 2 LASTPROP $XRERR UNIQUE?
J 0
(-3565 4485);
DISPLAY 0.638298 (-3565 4485);
PAINT MONO (-3565 4485);
DISPLAY INVISIBLE (-3565 4485);
WIRE 16 -1 (-2625 4725)(-2025 4725);
FORCEPROP 2 LAST SIG_NAME CPU0_THERMTRIP_R_N
J 0
(-2500 4735);
DISPLAY 0.489362 (-2500 4735);
WIRE 16 -1 (-3525 4425)(-2825 4425);
FORCEPROP 2 LAST SIG_NAME CPU0_XTRIG_R2_L7
J 0
(-3325 4435);
DISPLAY 0.489362 (-3325 4435);
FORCEPROP 2 LASTPROP $XRERR UNIQUE?
J 0
(-3565 4435);
DISPLAY 0.638298 (-3565 4435);
PAINT MONO (-3565 4435);
DISPLAY INVISIBLE (-3565 4435);
WIRE 16 -1 (-5025 3675)(-6125 3675);
FORCEPROP 2 LAST SIG_NAME TP_CPU0_TEST47_CCD3
J 0
(-5885 3685);
DISPLAY 0.489362 (-5885 3685);
FORCEPROP 2 LASTPROP $XRERR UNIQUE?
J 0
(-6365 3675);
DISPLAY 0.638298 (-6365 3675);
PAINT MONO (-6365 3675);
DISPLAY INVISIBLE (-6365 3675);
WIRE 16 -1 (-5025 3775)(-6125 3775);
FORCEPROP 2 LAST SIG_NAME TP_CPU0_TEST47_CCD1
J 0
(-5885 3785);
DISPLAY 0.489362 (-5885 3785);
FORCEPROP 2 LASTPROP $XRERR UNIQUE?
J 0
(-6365 3775);
DISPLAY 0.638298 (-6365 3775);
PAINT MONO (-6365 3775);
DISPLAY INVISIBLE (-6365 3775);
WIRE 16 -1 (-5025 3825)(-6125 3825);
FORCEPROP 2 LAST SIG_NAME TP_CPU0_TEST47_CCD0
J 0
(-5885 3835);
DISPLAY 0.489362 (-5885 3835);
FORCEPROP 2 LASTPROP $XRERR UNIQUE?
J 0
(-6365 3825);
DISPLAY 0.638298 (-6365 3825);
PAINT MONO (-6365 3825);
DISPLAY INVISIBLE (-6365 3825);
WIRE 16 -1 (-6125 3575)(-5025 3575);
FORCEPROP 2 LAST SIG_NAME TP_CPU0_TEST47_IOD0
J 0
(-5885 3585);
DISPLAY 0.489362 (-5885 3585);
FORCEPROP 2 LASTPROP $XRERR UNIQUE?
J 0
(-6365 3575);
DISPLAY 0.638298 (-6365 3575);
PAINT MONO (-6365 3575);
DISPLAY INVISIBLE (-6365 3575);
WIRE 16 -1 (-1200 2275)(-775 2275);
FORCEPROP 2 LAST SIG_NAME CPU0_BP1
J 0
(-1185 2285);
DISPLAY 0.489362 (-1185 2285);
WIRE 16 -1 (-1200 2325)(-775 2325);
FORCEPROP 2 LAST SIG_NAME CPU0_BP0
J 0
(-1185 2335);
DISPLAY 0.489362 (-1185 2335);
WIRE 16 -1 (-1375 2850)(-775 2850);
FORCEPROP 2 LAST SIG_NAME CPU0_XTRIG_R1_L6
J 0
(-1235 2860);
DISPLAY 0.489362 (-1235 2860);
FORCEPROP 2 LASTPROP $XRERR UNIQUE?
J 0
(-1475 2860);
DISPLAY 0.638298 (-1475 2860);
PAINT MONO (-1475 2860);
DISPLAY INVISIBLE (-1475 2860);
WIRE 16 -1 (-3525 5475)(-2750 5475);
FORCEPROP 2 LAST SIG_NAME NC_CPU0_AZ_SYNC
J 0
(-3315 5485);
DISPLAY 0.489362 (-3315 5485);
FORCEPROP 2 LASTPROP $XRERR UNIQUE?
J 0
(-2720 5475);
DISPLAY 0.638298 (-2720 5475);
PAINT MONO (-2720 5475);
DISPLAY INVISIBLE (-2720 5475);
WIRE 16 -1 (-3525 5525)(-2750 5525);
FORCEPROP 2 LAST SIG_NAME NC_CPU0_AZ_SDOUT
J 0
(-3315 5535);
DISPLAY 0.489362 (-3315 5535);
FORCEPROP 2 LASTPROP $XRERR UNIQUE?
J 0
(-2720 5525);
DISPLAY 0.638298 (-2720 5525);
PAINT MONO (-2720 5525);
DISPLAY INVISIBLE (-2720 5525);
WIRE 16 -1 (-3525 5575)(-2750 5575);
FORCEPROP 2 LAST SIG_NAME NC_CPU0_AZ_SDIN2
J 0
(-3315 5585);
DISPLAY 0.489362 (-3315 5585);
FORCEPROP 2 LASTPROP $XRERR UNIQUE?
J 0
(-2720 5575);
DISPLAY 0.638298 (-2720 5575);
PAINT MONO (-2720 5575);
DISPLAY INVISIBLE (-2720 5575);
WIRE 16 -1 (-3525 5625)(-2750 5625);
FORCEPROP 2 LAST SIG_NAME NC_CPU0_AZ_SDIN1
J 0
(-3315 5635);
DISPLAY 0.489362 (-3315 5635);
FORCEPROP 2 LASTPROP $XRERR UNIQUE?
J 0
(-2720 5625);
DISPLAY 0.638298 (-2720 5625);
PAINT MONO (-2720 5625);
DISPLAY INVISIBLE (-2720 5625);
WIRE 16 -1 (-3525 5675)(-2750 5675);
FORCEPROP 2 LAST SIG_NAME NC_CPU0_AZ_SDIN0
J 0
(-3315 5685);
DISPLAY 0.489362 (-3315 5685);
FORCEPROP 2 LASTPROP $XRERR UNIQUE?
J 0
(-2720 5675);
DISPLAY 0.638298 (-2720 5675);
PAINT MONO (-2720 5675);
DISPLAY INVISIBLE (-2720 5675);
WIRE 16 -1 (-3525 5725)(-2750 5725);
FORCEPROP 2 LAST SIG_NAME NC_CPU0_AZ_RST_N
J 0
(-3315 5735);
DISPLAY 0.489362 (-3315 5735);
FORCEPROP 2 LASTPROP $XRERR UNIQUE?
J 0
(-2720 5725);
DISPLAY 0.638298 (-2720 5725);
PAINT MONO (-2720 5725);
DISPLAY INVISIBLE (-2720 5725);
WIRE 16 -1 (-3525 5775)(-2750 5775);
FORCEPROP 2 LAST SIG_NAME NC_CPU0_AZ_BITCLK
J 0
(-3315 5785);
DISPLAY 0.489362 (-3315 5785);
FORCEPROP 2 LASTPROP $XRERR UNIQUE?
J 0
(-2720 5775);
DISPLAY 0.638298 (-2720 5775);
PAINT MONO (-2720 5775);
DISPLAY INVISIBLE (-2720 5775);
WIRE 16 -1 (-8600 2950)(-7775 2950);
FORCEPROP 2 LAST SIG_NAME CPU0_CORETYPE0
J 0
(-8275 2960);
DISPLAY 0.489362 (-8275 2960);
WIRE 16 -1 (-8600 2900)(-7775 2900);
FORCEPROP 2 LAST SIG_NAME CPU0_CORETYPE1
J 0
(-8275 2910);
DISPLAY 0.489362 (-8275 2910);
WIRE 16 -1 (-7775 2850)(-8600 2850);
FORCEPROP 2 LAST SIG_NAME CPU0_CORETYPE2
J 0
(-8275 2860);
DISPLAY 0.489362 (-8275 2860);
WIRE 16 -1 (-8600 3100)(-7775 3100);
FORCEPROP 2 LAST SIG_NAME CPU0_SP5R2
J 0
(-8275 3110);
DISPLAY 0.489362 (-8275 3110);
WIRE 16 -1 (-8600 3150)(-7775 3150);
FORCEPROP 2 LAST SIG_NAME CPU0_SP5R1
J 0
(-8275 3160);
DISPLAY 0.489362 (-8275 3160);
WIRE 16 -1 (-8600 3050)(-7775 3050);
FORCEPROP 2 LAST SIG_NAME CPU0_SP5R3
J 0
(-8275 3060);
DISPLAY 0.489362 (-8275 3060);
WIRE 16 -1 (-8600 3000)(-7775 3000);
FORCEPROP 2 LAST SIG_NAME CPU0_SP5R4
J 0
(-8275 3010);
DISPLAY 0.489362 (-8275 3010);
WIRE 16 -1 (-8675 4525)(-7825 4525);
FORCEPROP 2 LAST SIG_NAME CPU0_SA0
J 0
(-8310 4535);
DISPLAY 0.489362 (-8310 4535);
WIRE 16 -1 (-8675 4550)(-8675 4525);
WIRE 16 -1 (-8675 4525)(-8675 4450);
WIRE 16 -1 (-8550 4475)(-7825 4475);
FORCEPROP 2 LAST SIG_NAME CPU0_SA1
J 0
(-8310 4485);
DISPLAY 0.489362 (-8310 4485);
WIRE 16 -1 (-8550 4475)(-8550 4450);
WIRE 16 -1 (-8725 1000)(-7350 1000);
FORCEPROP 2 LAST SIG_NAME JTAG_CPU0_TRST_N
J 0
(-8560 1010);
DISPLAY 0.489362 (-8560 1010);
WIRE 16 -1 (-7350 1200)(-7350 1000);
WIRE 16 -1 (-7350 700)(-7350 1000);
WIRE 16 -1 (-8725 1100)(-8000 1100);
FORCEPROP 2 LAST SIG_NAME JTAG_CPU0_TDO
J 0
(-8560 1110);
DISPLAY 0.489362 (-8560 1110);
WIRE 16 -1 (-8000 1200)(-8000 1100);
WIRE 16 -1 (-8000 700)(-8000 1100);
WIRE 16 -1 (-8725 1050)(-7675 1050);
FORCEPROP 2 LAST SIG_NAME JTAG_CPU0_TDI
J 0
(-8560 1060);
DISPLAY 0.489362 (-8560 1060);
WIRE 16 -1 (-7675 1200)(-7675 1050);
WIRE 16 -1 (-7675 700)(-7675 1050);
WIRE 16 -1 (-8725 950)(-7025 950);
FORCEPROP 2 LAST SIG_NAME JTAG_CPU0_TCK
J 0
(-8560 960);
DISPLAY 0.489362 (-8560 960);
WIRE 16 -1 (-7025 1200)(-7025 950);
WIRE 16 -1 (-7025 700)(-7025 950);
WIRE 16 -1 (-8725 900)(-6675 900);
FORCEPROP 2 LAST SIG_NAME JTAG_CPU0_TMS
J 0
(-8560 910);
DISPLAY 0.489362 (-8560 910);
WIRE 16 -1 (-6675 1200)(-6675 900);
WIRE 16 -1 (-6675 700)(-6675 900);
WIRE 16 -1 (-8725 850)(-6375 850);
FORCEPROP 2 LAST SIG_NAME JTAG_CPU0_DBREQ_N
J 0
(-8560 860);
DISPLAY 0.489362 (-8560 860);
WIRE 16 -1 (-6375 850)(-6375 1200);
WIRE 16 -1 (-6375 700)(-6375 850);
WIRE 16 -1 (-5025 2275)(-6625 2275);
FORCEPROP 2 LAST SIG_NAME VSENSE_VSS_SENSE_B_P0
J 0
(-5975 2285);
DISPLAY 0.489362 (-5975 2285);
WIRE 16 -1 (-6625 2275)(-6775 2275);
WIRE 16 -1 (-6625 1675)(-6625 2275);
WIRE 16 -1 (-6475 1675)(-6475 2175);
WIRE 16 -1 (-6475 2175)(-5025 2175);
FORCEPROP 2 LAST SIG_NAME VSENSE_PVDD18_S5_P0_DN
J 2
(-5460 2185);
DISPLAY 0.489362 (-5460 2185);
WIRE 16 -1 (-6775 2175)(-6475 2175);
WIRE 16 -1 (-5025 2075)(-6350 2075);
FORCEPROP 2 LAST SIG_NAME VSENSE_PVDDIO_P0_DP
J 0
(-5960 2085);
DISPLAY 0.489362 (-5960 2085);
WIRE 16 -1 (-6350 2075)(-6775 2075);
WIRE 16 -1 (-6350 1675)(-6350 2075);
WIRE 16 -1 (-5025 2025)(-6275 2025);
FORCEPROP 2 LAST SIG_NAME VSENSE_PVDDCR_CPU1_P0_DP
J 0
(-5960 2035);
DISPLAY 0.489362 (-5960 2035);
WIRE 16 -1 (-6275 1675)(-6275 2025);
WIRE 16 -1 (-6275 2025)(-6775 2025);
WIRE 16 -1 (-5025 2325)(-6700 2325);
FORCEPROP 2 LAST SIG_NAME VSENSE_VSS_SENSE_A_P0
J 0
(-5975 2335);
DISPLAY 0.489362 (-5975 2335);
WIRE 16 -1 (-6700 2325)(-6775 2325);
WIRE 16 -1 (-6700 1675)(-6700 2325);
WIRE 16 -1 (-6775 1975)(-6200 1975);
WIRE 16 -1 (-6200 1975)(-5025 1975);
FORCEPROP 2 LAST SIG_NAME VSENSE_PVDDCR_CPU0_P0_DP
J 2
(-5410 1985);
DISPLAY 0.489362 (-5410 1985);
WIRE 16 -1 (-6200 1675)(-6200 1975);
WIRE 16 -1 (-5025 2225)(-6550 2225);
FORCEPROP 2 LAST SIG_NAME VSENSE_VSS_SENSE_C_P0
J 2
(-5485 2235);
DISPLAY 0.489362 (-5485 2235);
WIRE 16 -1 (-6550 2225)(-6775 2225);
WIRE 16 -1 (-6550 1675)(-6550 2225);
WIRE 16 -1 (-5025 1925)(-6125 1925);
FORCEPROP 2 LAST SIG_NAME VSENSE_PVDD11_S3_P0_DP
J 2
(-5460 1935);
DISPLAY 0.489362 (-5460 1935);
WIRE 16 -1 (-6125 1675)(-6125 1925);
WIRE 16 -1 (-6125 1925)(-6775 1925);
WIRE 16 -1 (-5975 1875)(-5025 1875);
FORCEPROP 2 LAST SIG_NAME TP_VSENSE_PVDD33_S5_P0
J 2
(-5445 1885);
DISPLAY 0.489362 (-5445 1885);
FORCEPROP 2 LASTPROP $XRERR UNIQUE?
J 0
(-6215 1875);
DISPLAY 0.638298 (-6215 1875);
PAINT MONO (-6215 1875);
DISPLAY INVISIBLE (-6215 1875);
WIRE 16 -1 (-6775 1775)(-5900 1775);
WIRE 16 -1 (-5900 1775)(-5025 1775);
FORCEPROP 2 LAST SIG_NAME VSENSE_PVDDCR_SOC_P0_DP
J 2
(-5435 1785);
DISPLAY 0.489362 (-5435 1785);
WIRE 16 -1 (-5900 1675)(-5900 1775);
WIRE 16 -1 (-6775 1825)(-5975 1825);
WIRE 16 -1 (-5975 1825)(-5025 1825);
FORCEPROP 2 LAST SIG_NAME VSENSE_PVDD18_S5_P0_DP
J 2
(-5460 1835);
DISPLAY 0.489362 (-5460 1835);
WIRE 16 -1 (-5975 1825)(-5975 1675);
WIRE 16 -1 (-5025 3725)(-6125 3725);
FORCEPROP 2 LAST SIG_NAME TP_CPU0_TEST47_CCD2
J 0
(-5885 3735);
DISPLAY 0.489362 (-5885 3735);
FORCEPROP 2 LASTPROP $XRERR UNIQUE?
J 0
(-6365 3725);
DISPLAY 0.638298 (-6365 3725);
PAINT MONO (-6365 3725);
DISPLAY INVISIBLE (-6365 3725);
WIRE 16 -1 (-5025 3525)(-6125 3525);
FORCEPROP 2 LAST SIG_NAME TP_CPU0_TEST47_IOD1
J 0
(-5885 3535);
DISPLAY 0.489362 (-5885 3535);
FORCEPROP 2 LASTPROP $XRERR UNIQUE?
J 0
(-6365 3525);
DISPLAY 0.638298 (-6365 3525);
PAINT MONO (-6365 3525);
DISPLAY INVISIBLE (-6365 3525);
WIRE 16 -1 (-5025 3225)(-6075 3225);
FORCEPROP 2 LAST SIG_NAME TP_CPU0_TEST50_IOD
J 0
(-5945 3235);
DISPLAY 0.489362 (-5945 3235);
FORCEPROP 2 LASTPROP $XRERR UNIQUE?
J 0
(-6315 3225);
DISPLAY 0.638298 (-6315 3225);
PAINT MONO (-6315 3225);
DISPLAY INVISIBLE (-6315 3225);
WIRE 16 -1 (-5025 2425)(-6075 2425);
FORCEPROP 2 LAST SIG_NAME CPU0_CORETYPE2
J 2
(-5635 2435);
DISPLAY 0.489362 (-5635 2435);
WIRE 16 -1 (-5025 3075)(-6075 3075);
FORCEPROP 2 LAST SIG_NAME PRSNT_CPU0_N
J 2
(-5685 3085);
DISPLAY 0.489362 (-5685 3085);
WIRE 16 -1 (-5025 2525)(-6075 2525);
FORCEPROP 2 LAST SIG_NAME CPU0_CORETYPE0
J 2
(-5635 2535);
DISPLAY 0.489362 (-5635 2535);
WIRE 16 -1 (-6075 2475)(-5025 2475);
FORCEPROP 2 LAST SIG_NAME CPU0_CORETYPE1
J 2
(-5635 2485);
DISPLAY 0.489362 (-5635 2485);
WIRE 16 -1 (-5025 2775)(-6075 2775);
FORCEPROP 2 LAST SIG_NAME CPU0_SP5R1
J 2
(-5735 2785);
DISPLAY 0.489362 (-5735 2785);
WIRE 16 -1 (-6075 2725)(-5025 2725);
FORCEPROP 2 LAST SIG_NAME CPU0_SP5R2
J 2
(-5735 2735);
DISPLAY 0.489362 (-5735 2735);
WIRE 16 -1 (-5025 2675)(-6075 2675);
FORCEPROP 2 LAST SIG_NAME CPU0_SP5R3
J 2
(-5735 2685);
DISPLAY 0.489362 (-5735 2685);
WIRE 16 -1 (-6075 2625)(-5025 2625);
FORCEPROP 2 LAST SIG_NAME CPU0_SP5R4
J 2
(-5735 2635);
DISPLAY 0.489362 (-5735 2635);
WIRE 16 -1 (-5025 2975)(-6075 2975);
FORCEPROP 2 LAST SIG_NAME CPU0_SA0
J 0
(-5960 2985);
DISPLAY 0.489362 (-5960 2985);
WIRE 16 -1 (-5025 2925)(-6075 2925);
FORCEPROP 2 LAST SIG_NAME CPU0_SA1
J 0
(-5960 2935);
DISPLAY 0.489362 (-5960 2935);
WIRE 16 -1 (-7475 5275)(-6450 5275);
FORCEPROP 2 LAST SIG_NAME SVID_PVDDCR_CPU1_P0_SVD_R
J 0
(-7275 5285);
DISPLAY 0.489362 (-7275 5285);
WIRE 16 -1 (-6450 5325)(-7475 5325);
FORCEPROP 2 LAST SIG_NAME SVID_PVDDCR_CPU1_P0_SVC_R
J 0
(-7275 5335);
DISPLAY 0.489362 (-7275 5335);
WIRE 16 -1 (-7475 5475)(-6450 5475);
FORCEPROP 2 LAST SIG_NAME SVID_PVDDCR_CPU0_P0_SVD_R
J 0
(-7275 5485);
DISPLAY 0.489362 (-7275 5485);
WIRE 16 -1 (-7475 5525)(-6450 5525);
FORCEPROP 2 LAST SIG_NAME SVID_PVDDCR_CPU0_P0_SVC_R
J 0
(-7275 5535);
DISPLAY 0.489362 (-7275 5535);
WIRE 16 -1 (-6250 5475)(-5025 5475);
FORCEPROP 2 LAST SIG_NAME SVID_PVDDCR_CPU0_P0_SVD
J 0
(-5760 5485);
DISPLAY 0.489362 (-5760 5485);
FORCEPROP 2 LASTPROP $XRERR UNIQUE?
J 0
(-6000 5485);
DISPLAY 0.638298 (-6000 5485);
PAINT MONO (-6000 5485);
DISPLAY INVISIBLE (-6000 5485);
WIRE 16 -1 (-6250 5275)(-5025 5275);
FORCEPROP 2 LAST SIG_NAME SVID_PVDDCR_CPU1_P0_SVD
J 0
(-5685 5285);
DISPLAY 0.489362 (-5685 5285);
FORCEPROP 2 LASTPROP $XRERR UNIQUE?
J 0
(-5925 5285);
DISPLAY 0.638298 (-5925 5285);
PAINT MONO (-5925 5285);
DISPLAY INVISIBLE (-5925 5285);
WIRE 16 -1 (-6250 5525)(-5025 5525);
FORCEPROP 2 LAST SIG_NAME SVID_PVDDCR_CPU0_P0_SVC
J 0
(-5760 5535);
DISPLAY 0.489362 (-5760 5535);
FORCEPROP 2 LASTPROP $XRERR UNIQUE?
J 0
(-6000 5535);
DISPLAY 0.638298 (-6000 5535);
PAINT MONO (-6000 5535);
DISPLAY INVISIBLE (-6000 5535);
WIRE 16 -1 (-6250 5325)(-5025 5325);
FORCEPROP 2 LAST SIG_NAME SVID_PVDDCR_CPU1_P0_SVC
J 0
(-5685 5335);
DISPLAY 0.489362 (-5685 5335);
FORCEPROP 2 LASTPROP $XRERR UNIQUE?
J 0
(-5925 5335);
DISPLAY 0.638298 (-5925 5335);
PAINT MONO (-5925 5335);
DISPLAY INVISIBLE (-5925 5335);
WIRE 16 -1 (-6525 4575)(-5825 4575);
FORCEPROP 2 LAST SIG_NAME JTAG_CPU0_TDO
J 0
(-6435 4585);
DISPLAY 0.489362 (-6435 4585);
WIRE 16 -1 (-5025 4575)(-5625 4575);
FORCEPROP 2 LAST SIG_NAME JTAG_CPU0_R_TDO
J 0
(-5560 4585);
DISPLAY 0.489362 (-5560 4585);
FORCEPROP 2 LASTPROP $XRERR UNIQUE?
J 0
(-5800 4585);
DISPLAY 0.638298 (-5800 4585);
PAINT MONO (-5800 4585);
DISPLAY INVISIBLE (-5800 4585);
WIRE 16 -1 (-6075 4475)(-5025 4475);
FORCEPROP 2 LAST SIG_NAME JTAG_CPU0_TRST_N
J 0
(-5910 4485);
DISPLAY 0.489362 (-5910 4485);
WIRE 16 -1 (-6075 4375)(-5025 4375);
FORCEPROP 2 LAST SIG_NAME JTAG_CPU0_TMS
J 0
(-5910 4385);
DISPLAY 0.489362 (-5910 4385);
WIRE 16 -1 (-5025 4275)(-6075 4275);
FORCEPROP 2 LAST SIG_NAME JTAG_CPU0_DBREQ_N
J 0
(-5910 4285);
DISPLAY 0.489362 (-5910 4285);
WIRE 16 -1 (-5025 4525)(-6075 4525);
FORCEPROP 2 LAST SIG_NAME JTAG_CPU0_TDI
J 0
(-5910 4535);
DISPLAY 0.489362 (-5910 4535);
WIRE 16 -1 (-5700 5425)(-5025 5425);
FORCEPROP 2 LAST SIG_NAME SVID_PVDDCR_CPU0_P0_SVTO
J 0
(-5685 5435);
DISPLAY 0.489362 (-5685 5435);
WIRE 16 -1 (-5700 5225)(-5025 5225);
FORCEPROP 2 LAST SIG_NAME SVID_PVDDCR_CPU1_P0_SVTO
J 0
(-5685 5235);
DISPLAY 0.489362 (-5685 5235);
WIRE 16 -1 (-5025 4875)(-6075 4875);
FORCEPROP 2 LAST SIG_NAME SMB_APML_CPU0_SCL
J 2
(-5510 4885);
DISPLAY 0.489362 (-5510 4885);
WIRE 16 -1 (-5025 4825)(-6075 4825);
FORCEPROP 2 LAST SIG_NAME SMB_APML_CPU0_SDA
J 2
(-5510 4835);
DISPLAY 0.489362 (-5510 4835);
WIRE 16 -1 (-5025 5675)(-5700 5675);
FORCEPROP 2 LAST SIG_NAME FM_P0_PCC0_N
J 0
(-5685 5685);
DISPLAY 0.489362 (-5685 5685);
WIRE 16 -1 (-5025 5625)(-5700 5625);
FORCEPROP 2 LAST SIG_NAME FM_P0_PCC1_N
J 0
(-5685 5635);
DISPLAY 0.489362 (-5685 5635);
WIRE 16 -1 (-3525 1575)(-2600 1575);
FORCEPROP 2 LAST SIG_NAME TP_UART_CPU0_UART0_RTS_N
J 0
(-3285 1585);
DISPLAY 0.489362 (-3285 1585);
FORCEPROP 2 LASTPROP $XRERR UNIQUE?
J 0
(-2570 1575);
DISPLAY 0.638298 (-2570 1575);
PAINT MONO (-2570 1575);
DISPLAY INVISIBLE (-2570 1575);
WIRE 16 -1 (-3525 1525)(-2725 1525);
FORCEPROP 2 LAST SIG_NAME TP_CPU0_UART0_INTR
J 0
(-3270 1535);
DISPLAY 0.489362 (-3270 1535);
FORCEPROP 2 LASTPROP $XRERR UNIQUE?
J 0
(-2695 1525);
DISPLAY 0.638298 (-2695 1525);
PAINT MONO (-2695 1525);
DISPLAY INVISIBLE (-2695 1525);
WIRE 16 -1 (-3525 1475)(-2475 1475);
FORCEPROP 2 LAST SIG_NAME UART_CPU0_UART0_R_TX
J 0
(-3285 1485);
DISPLAY 0.489362 (-3285 1485);
FORCEPROP 2 LASTPROP $XRERR UNIQUE?
J 0
(-3525 1485);
DISPLAY 0.638298 (-3525 1485);
PAINT MONO (-3525 1485);
DISPLAY INVISIBLE (-3525 1485);
WIRE 16 -1 (-3525 1625)(-2600 1625);
FORCEPROP 2 LAST SIG_NAME FM_BIOS_USB_RECOVERY_R
J 0
(-3385 1635);
DISPLAY 0.489362 (-3385 1635);
FORCEPROP 2 LASTPROP $XRERR UNIQUE?
J 0
(-3625 1635);
DISPLAY 0.638298 (-3625 1635);
PAINT MONO (-3625 1635);
DISPLAY INVISIBLE (-3625 1635);
WIRE 16 -1 (-2475 1375)(-3525 1375);
FORCEPROP 2 LAST SIG_NAME UART_CPU0_SCM_UART1_R_TX
J 0
(-3285 1385);
DISPLAY 0.489362 (-3285 1385);
FORCEPROP 2 LASTPROP $XRERR UNIQUE?
J 0
(-3525 1385);
DISPLAY 0.638298 (-3525 1385);
PAINT MONO (-3525 1385);
DISPLAY INVISIBLE (-3525 1385);
WIRE 16 -1 (-3525 1825)(-2750 1825);
FORCEPROP 2 LAST SIG_NAME TP_CPU0_TEST4_IOD
J 0
(-3290 1835);
DISPLAY 0.489362 (-3290 1835);
FORCEPROP 2 LASTPROP $XRERR UNIQUE?
J 0
(-2720 1825);
DISPLAY 0.638298 (-2720 1825);
PAINT MONO (-2720 1825);
DISPLAY INVISIBLE (-2720 1825);
WIRE 16 -1 (-3525 1725)(-2750 1725);
FORCEPROP 2 LAST SIG_NAME TP_CPU0_TEST5_IOD
J 0
(-3290 1735);
DISPLAY 0.489362 (-3290 1735);
FORCEPROP 2 LASTPROP $XRERR UNIQUE?
J 0
(-2720 1725);
DISPLAY 0.638298 (-2720 1725);
PAINT MONO (-2720 1725);
DISPLAY INVISIBLE (-2720 1725);
WIRE 16 -1 (-3525 2025)(-2750 2025);
FORCEPROP 2 LAST SIG_NAME TP_CPU0_TEST5_CCD9
J 0
(-3290 2035);
DISPLAY 0.489362 (-3290 2035);
FORCEPROP 2 LASTPROP $XRERR UNIQUE?
J 0
(-2720 2025);
DISPLAY 0.638298 (-2720 2025);
PAINT MONO (-2720 2025);
DISPLAY INVISIBLE (-2720 2025);
WIRE 16 -1 (-3525 1975)(-2750 1975);
FORCEPROP 2 LAST SIG_NAME TP_CPU0_TEST5_CCD10
J 0
(-3290 1985);
DISPLAY 0.489362 (-3290 1985);
FORCEPROP 2 LASTPROP $XRERR UNIQUE?
J 0
(-2720 1975);
DISPLAY 0.638298 (-2720 1975);
PAINT MONO (-2720 1975);
DISPLAY INVISIBLE (-2720 1975);
WIRE 16 -1 (-3525 1925)(-2750 1925);
FORCEPROP 2 LAST SIG_NAME TP_CPU0_TEST5_CCD11
J 0
(-3290 1935);
DISPLAY 0.489362 (-3290 1935);
FORCEPROP 2 LASTPROP $XRERR UNIQUE?
J 0
(-2720 1925);
DISPLAY 0.638298 (-2720 1925);
PAINT MONO (-2720 1925);
DISPLAY INVISIBLE (-2720 1925);
WIRE 16 -1 (-3525 1125)(-2750 1125);
FORCEPROP 2 LAST SIG_NAME TP_CPU0_TEST41_IDO
J 0
(-3235 1135);
DISPLAY 0.489362 (-3235 1135);
FORCEPROP 2 LASTPROP $XRERR UNIQUE?
J 0
(-2720 1125);
DISPLAY 0.638298 (-2720 1125);
PAINT MONO (-2720 1125);
DISPLAY INVISIBLE (-2720 1125);
WIRE 16 -1 (-3525 3375)(-2750 3375);
FORCEPROP 2 LAST SIG_NAME TP_CPU0_TEST6_X3D4
J 0
(-3290 3385);
DISPLAY 0.489362 (-3290 3385);
FORCEPROP 2 LASTPROP $XRERR UNIQUE?
J 0
(-2720 3375);
DISPLAY 0.638298 (-2720 3375);
PAINT MONO (-2720 3375);
DISPLAY INVISIBLE (-2720 3375);
WIRE 16 -1 (-3525 2475)(-2750 2475);
FORCEPROP 2 LAST SIG_NAME TP_CPU0_TEST5_CCD0
J 0
(-3290 2485);
DISPLAY 0.489362 (-3290 2485);
FORCEPROP 2 LASTPROP $XRERR UNIQUE?
J 0
(-2720 2475);
DISPLAY 0.638298 (-2720 2475);
PAINT MONO (-2720 2475);
DISPLAY INVISIBLE (-2720 2475);
WIRE 16 -1 (-3525 3325)(-2750 3325);
FORCEPROP 2 LAST SIG_NAME TP_CPU0_TEST6_X3D5
J 0
(-3290 3335);
DISPLAY 0.489362 (-3290 3335);
FORCEPROP 2 LASTPROP $XRERR UNIQUE?
J 0
(-2720 3325);
DISPLAY 0.638298 (-2720 3325);
PAINT MONO (-2720 3325);
DISPLAY INVISIBLE (-2720 3325);
WIRE 16 -1 (-3525 2425)(-2750 2425);
FORCEPROP 2 LAST SIG_NAME TP_CPU0_TEST5_CCD1
J 0
(-3290 2435);
DISPLAY 0.489362 (-3290 2435);
FORCEPROP 2 LASTPROP $XRERR UNIQUE?
J 0
(-2720 2425);
DISPLAY 0.638298 (-2720 2425);
PAINT MONO (-2720 2425);
DISPLAY INVISIBLE (-2720 2425);
WIRE 16 -1 (-3525 3125)(-2750 3125);
FORCEPROP 2 LAST SIG_NAME TP_CPU0_TEST4_CCD0
J 0
(-3290 3135);
DISPLAY 0.489362 (-3290 3135);
FORCEPROP 2 LASTPROP $XRERR UNIQUE?
J 0
(-2720 3125);
DISPLAY 0.638298 (-2720 3125);
PAINT MONO (-2720 3125);
DISPLAY INVISIBLE (-2720 3125);
WIRE 16 -1 (-3525 3075)(-2750 3075);
FORCEPROP 2 LAST SIG_NAME TP_CPU0_TEST4_CCD1
J 0
(-3290 3085);
DISPLAY 0.489362 (-3290 3085);
FORCEPROP 2 LASTPROP $XRERR UNIQUE?
J 0
(-2720 3075);
DISPLAY 0.638298 (-2720 3075);
PAINT MONO (-2720 3075);
DISPLAY INVISIBLE (-2720 3075);
WIRE 16 -1 (-3525 2325)(-2750 2325);
FORCEPROP 2 LAST SIG_NAME TP_CPU0_TEST5_CCD3
J 0
(-3290 2335);
DISPLAY 0.489362 (-3290 2335);
FORCEPROP 2 LASTPROP $XRERR UNIQUE?
J 0
(-2720 2325);
DISPLAY 0.638298 (-2720 2325);
PAINT MONO (-2720 2325);
DISPLAY INVISIBLE (-2720 2325);
WIRE 16 -1 (-3525 3025)(-2750 3025);
FORCEPROP 2 LAST SIG_NAME TP_CPU0_TEST4_CCD2
J 0
(-3290 3035);
DISPLAY 0.489362 (-3290 3035);
FORCEPROP 2 LASTPROP $XRERR UNIQUE?
J 0
(-2720 3025);
DISPLAY 0.638298 (-2720 3025);
PAINT MONO (-2720 3025);
DISPLAY INVISIBLE (-2720 3025);
WIRE 16 -1 (-3525 2275)(-2750 2275);
FORCEPROP 2 LAST SIG_NAME TP_CPU0_TEST5_CCD4
J 0
(-3290 2285);
DISPLAY 0.489362 (-3290 2285);
FORCEPROP 2 LASTPROP $XRERR UNIQUE?
J 0
(-2720 2275);
DISPLAY 0.638298 (-2720 2275);
PAINT MONO (-2720 2275);
DISPLAY INVISIBLE (-2720 2275);
WIRE 16 -1 (-3525 2975)(-2750 2975);
FORCEPROP 2 LAST SIG_NAME TP_CPU0_TEST4_CCD3
J 0
(-3290 2985);
DISPLAY 0.489362 (-3290 2985);
FORCEPROP 2 LASTPROP $XRERR UNIQUE?
J 0
(-2720 2975);
DISPLAY 0.638298 (-2720 2975);
PAINT MONO (-2720 2975);
DISPLAY INVISIBLE (-2720 2975);
WIRE 16 -1 (-3525 3225)(-2750 3225);
FORCEPROP 2 LAST SIG_NAME TP_CPU0_TEST6_IOD
J 0
(-3290 3235);
DISPLAY 0.489362 (-3290 3235);
FORCEPROP 2 LASTPROP $XRERR UNIQUE?
J 0
(-2720 3225);
DISPLAY 0.638298 (-2720 3225);
PAINT MONO (-2720 3225);
DISPLAY INVISIBLE (-2720 3225);
WIRE 16 -1 (-3525 2225)(-2750 2225);
FORCEPROP 2 LAST SIG_NAME TP_CPU0_TEST5_CCD5
J 0
(-3290 2235);
DISPLAY 0.489362 (-3290 2235);
FORCEPROP 2 LASTPROP $XRERR UNIQUE?
J 0
(-2720 2225);
DISPLAY 0.638298 (-2720 2225);
PAINT MONO (-2720 2225);
DISPLAY INVISIBLE (-2720 2225);
WIRE 16 -1 (-3525 2925)(-2750 2925);
FORCEPROP 2 LAST SIG_NAME TP_CPU0_TEST4_CCD4
J 0
(-3290 2935);
DISPLAY 0.489362 (-3290 2935);
FORCEPROP 2 LASTPROP $XRERR UNIQUE?
J 0
(-2720 2925);
DISPLAY 0.638298 (-2720 2925);
PAINT MONO (-2720 2925);
DISPLAY INVISIBLE (-2720 2925);
WIRE 16 -1 (-3525 2175)(-2750 2175);
FORCEPROP 2 LAST SIG_NAME TP_CPU0_TEST5_CCD6
J 0
(-3290 2185);
DISPLAY 0.489362 (-3290 2185);
FORCEPROP 2 LASTPROP $XRERR UNIQUE?
J 0
(-2720 2175);
DISPLAY 0.638298 (-2720 2175);
PAINT MONO (-2720 2175);
DISPLAY INVISIBLE (-2720 2175);
WIRE 16 -1 (-3525 2875)(-2750 2875);
FORCEPROP 2 LAST SIG_NAME TP_CPU0_TEST4_CCD5
J 0
(-3290 2885);
DISPLAY 0.489362 (-3290 2885);
FORCEPROP 2 LASTPROP $XRERR UNIQUE?
J 0
(-2720 2875);
DISPLAY 0.638298 (-2720 2875);
PAINT MONO (-2720 2875);
DISPLAY INVISIBLE (-2720 2875);
WIRE 16 -1 (-3525 2125)(-2750 2125);
FORCEPROP 2 LAST SIG_NAME TP_CPU0_TEST5_CCD7
J 0
(-3290 2135);
DISPLAY 0.489362 (-3290 2135);
FORCEPROP 2 LASTPROP $XRERR UNIQUE?
J 0
(-2720 2125);
DISPLAY 0.638298 (-2720 2125);
PAINT MONO (-2720 2125);
DISPLAY INVISIBLE (-2720 2125);
WIRE 16 -1 (-3525 2825)(-2750 2825);
FORCEPROP 2 LAST SIG_NAME TP_CPU0_TEST4_CCD6
J 0
(-3290 2835);
DISPLAY 0.489362 (-3290 2835);
FORCEPROP 2 LASTPROP $XRERR UNIQUE?
J 0
(-2720 2825);
DISPLAY 0.638298 (-2720 2825);
PAINT MONO (-2720 2825);
DISPLAY INVISIBLE (-2720 2825);
WIRE 16 -1 (-3525 2075)(-2750 2075);
FORCEPROP 2 LAST SIG_NAME TP_CPU0_TEST5_CCD8
J 0
(-3290 2085);
DISPLAY 0.489362 (-3290 2085);
FORCEPROP 2 LASTPROP $XRERR UNIQUE?
J 0
(-2720 2075);
DISPLAY 0.638298 (-2720 2075);
PAINT MONO (-2720 2075);
DISPLAY INVISIBLE (-2720 2075);
WIRE 16 -1 (-3525 2775)(-2750 2775);
FORCEPROP 2 LAST SIG_NAME TP_CPU0_TEST4_CCD7
J 0
(-3290 2785);
DISPLAY 0.489362 (-3290 2785);
FORCEPROP 2 LASTPROP $XRERR UNIQUE?
J 0
(-2720 2775);
DISPLAY 0.638298 (-2720 2775);
PAINT MONO (-2720 2775);
DISPLAY INVISIBLE (-2720 2775);
WIRE 16 -1 (-3525 2725)(-2750 2725);
FORCEPROP 2 LAST SIG_NAME TP_CPU0_TEST4_CCD8
J 0
(-3290 2735);
DISPLAY 0.489362 (-3290 2735);
FORCEPROP 2 LASTPROP $XRERR UNIQUE?
J 0
(-2720 2725);
DISPLAY 0.638298 (-2720 2725);
PAINT MONO (-2720 2725);
DISPLAY INVISIBLE (-2720 2725);
WIRE 16 -1 (-3525 2625)(-2750 2625);
FORCEPROP 2 LAST SIG_NAME TP_CPU0_TEST4_CCD10
J 0
(-3290 2635);
DISPLAY 0.489362 (-3290 2635);
FORCEPROP 2 LASTPROP $XRERR UNIQUE?
J 0
(-2720 2625);
DISPLAY 0.638298 (-2720 2625);
PAINT MONO (-2720 2625);
DISPLAY INVISIBLE (-2720 2625);
WIRE 16 -1 (-3525 2675)(-2750 2675);
FORCEPROP 2 LAST SIG_NAME TP_CPU0_TEST4_CCD9
J 0
(-3290 2685);
DISPLAY 0.489362 (-3290 2685);
FORCEPROP 2 LASTPROP $XRERR UNIQUE?
J 0
(-2720 2675);
DISPLAY 0.638298 (-2720 2675);
PAINT MONO (-2720 2675);
DISPLAY INVISIBLE (-2720 2675);
WIRE 16 -1 (-3525 2575)(-2750 2575);
FORCEPROP 2 LAST SIG_NAME TP_CPU0_TEST4_CCD11
J 0
(-3290 2585);
DISPLAY 0.489362 (-3290 2585);
FORCEPROP 2 LASTPROP $XRERR UNIQUE?
J 0
(-2720 2575);
DISPLAY 0.638298 (-2720 2575);
PAINT MONO (-2720 2575);
DISPLAY INVISIBLE (-2720 2575);
WIRE 16 -1 (-3525 3575)(-2750 3575);
FORCEPROP 2 LAST SIG_NAME TP_CPU0_TEST6_X3D0
J 0
(-3290 3585);
DISPLAY 0.489362 (-3290 3585);
FORCEPROP 2 LASTPROP $XRERR UNIQUE?
J 0
(-2720 3575);
DISPLAY 0.638298 (-2720 3575);
PAINT MONO (-2720 3575);
DISPLAY INVISIBLE (-2720 3575);
WIRE 16 -1 (-3525 3525)(-2750 3525);
FORCEPROP 2 LAST SIG_NAME TP_CPU0_TEST6_X3D1
J 0
(-3290 3535);
DISPLAY 0.489362 (-3290 3535);
FORCEPROP 2 LASTPROP $XRERR UNIQUE?
J 0
(-2720 3525);
DISPLAY 0.638298 (-2720 3525);
PAINT MONO (-2720 3525);
DISPLAY INVISIBLE (-2720 3525);
WIRE 16 -1 (-3525 3475)(-2750 3475);
FORCEPROP 2 LAST SIG_NAME TP_CPU0_TEST6_X3D2
J 0
(-3290 3485);
DISPLAY 0.489362 (-3290 3485);
FORCEPROP 2 LASTPROP $XRERR UNIQUE?
J 0
(-2720 3475);
DISPLAY 0.638298 (-2720 3475);
PAINT MONO (-2720 3475);
DISPLAY INVISIBLE (-2720 3475);
WIRE 16 -1 (-3525 3425)(-2750 3425);
FORCEPROP 2 LAST SIG_NAME TP_CPU0_TEST6_X3D3
J 0
(-3290 3435);
DISPLAY 0.489362 (-3290 3435);
FORCEPROP 2 LASTPROP $XRERR UNIQUE?
J 0
(-2720 3425);
DISPLAY 0.638298 (-2720 3425);
PAINT MONO (-2720 3425);
DISPLAY INVISIBLE (-2720 3425);
WIRE 16 -1 (-3525 2375)(-2750 2375);
FORCEPROP 2 LAST SIG_NAME TP_CPU0_TEST5_CCD2
J 0
(-3290 2385);
DISPLAY 0.489362 (-3290 2385);
FORCEPROP 2 LASTPROP $XRERR UNIQUE?
J 0
(-2720 2375);
DISPLAY 0.638298 (-2720 2375);
PAINT MONO (-2720 2375);
DISPLAY INVISIBLE (-2720 2375);
WIRE 16 -1 (-2275 1475)(-1450 1475);
FORCEPROP 2 LAST SIG_NAME UART_CPU0_UART0_TX
J 0
(-2150 1485);
DISPLAY 0.489362 (-2150 1485);
WIRE 16 -1 (-3525 1425)(-1450 1425);
FORCEPROP 2 LAST SIG_NAME UART_CPU0_UART0_RX
J 0
(-2150 1435);
DISPLAY 0.489362 (-2150 1435);
WIRE 16 -1 (-3525 1325)(-1450 1325);
FORCEPROP 2 LAST SIG_NAME UART_CPU0_SCM_UART1_RX
J 0
(-2150 1335);
DISPLAY 0.489362 (-2150 1335);
WIRE 16 -1 (-1450 1375)(-2275 1375);
FORCEPROP 2 LAST SIG_NAME UART_CPU0_SCM_UART1_TX
J 0
(-2150 1385);
DISPLAY 0.489362 (-2150 1385);
WIRE 16 -1 (-1575 2800)(-2050 2800);
FORCEPROP 2 LAST SIG_NAME CPU0_XTRIG_L7
J 0
(-1960 2810);
DISPLAY 0.489362 (-1960 2810);
WIRE 16 -1 (-1575 2850)(-2050 2850);
FORCEPROP 2 LAST SIG_NAME CPU0_XTRIG_L6
J 0
(-1960 2860);
DISPLAY 0.489362 (-1960 2860);
WIRE 16 -1 (-1575 2900)(-2050 2900);
FORCEPROP 2 LAST SIG_NAME CPU0_XTRIG_L5
J 0
(-1960 2910);
DISPLAY 0.489362 (-1960 2910);
WIRE 16 -1 (-1575 2950)(-2050 2950);
FORCEPROP 2 LAST SIG_NAME CPU0_XTRIG_L4
J 0
(-1960 2960);
DISPLAY 0.489362 (-1960 2960);
WIRE 16 -1 (-2400 1625)(-1625 1625);
FORCEPROP 2 LAST SIG_NAME FM_BIOS_USB_RECOVERY
J 0
(-2310 1635);
DISPLAY 0.489362 (-2310 1635);
WIRE 16 -1 (-1375 2900)(-775 2900);
FORCEPROP 2 LAST SIG_NAME CPU0_XTRIG_R1_L5
J 0
(-1235 2910);
DISPLAY 0.489362 (-1235 2910);
FORCEPROP 2 LASTPROP $XRERR UNIQUE?
J 0
(-1475 2910);
DISPLAY 0.638298 (-1475 2910);
PAINT MONO (-1475 2910);
DISPLAY INVISIBLE (-1475 2910);
WIRE 16 -1 (-1375 2950)(-775 2950);
FORCEPROP 2 LAST SIG_NAME CPU0_XTRIG_R1_L4
J 0
(-1235 2960);
DISPLAY 0.489362 (-1235 2960);
FORCEPROP 2 LASTPROP $XRERR UNIQUE?
J 0
(-1475 2960);
DISPLAY 0.638298 (-1475 2960);
PAINT MONO (-1475 2960);
DISPLAY INVISIBLE (-1475 2960);
WIRE 16 -1 (-1200 2175)(-775 2175);
FORCEPROP 2 LAST SIG_NAME CPU0_BP3
J 0
(-1185 2185);
DISPLAY 0.489362 (-1185 2185);
WIRE 16 -1 (-1200 2225)(-775 2225);
FORCEPROP 2 LAST SIG_NAME CPU0_BP2
J 0
(-1185 2235);
DISPLAY 0.489362 (-1185 2235);
WIRE 16 -1 (-3525 4875)(-2825 4875);
FORCEPROP 2 LAST SIG_NAME APML_CPU0_ALERT_N
J 0
(-3325 4885);
DISPLAY 0.489362 (-3325 4885);
FORCEPROP 2 LASTPROP $XR0 27 
J 0
(-3390 4885);
DISPLAY 0.638298 (-3390 4885);
PAINT MONO (-3390 4885);
WIRE 16 -1 (-3525 4725)(-2825 4725);
FORCEPROP 2 LAST SIG_NAME CPU0_THERMTRIP_N
J 0
(-3325 4735);
DISPLAY 0.489362 (-3325 4735);
FORCEPROP 2 LASTPROP $XR0 27 
J 0
(-3390 4735);
DISPLAY 0.638298 (-3390 4735);
PAINT MONO (-3390 4735);
WIRE 16 -1 (-3525 4775)(-2025 4775);
FORCEPROP 2 LAST SIG_NAME CPU0_PROCHOT_N
J 0
(-3325 4785);
DISPLAY 0.489362 (-3325 4785);
WIRE 16 -1 (-675 5550)(-1475 5550);
FORCEPROP 2 LAST SIG_NAME CPU0_BP1
J 0
(-1450 5560);
DISPLAY 0.489362 (-1450 5560);
WIRE 16 -1 (-675 5600)(-1475 5600);
FORCEPROP 2 LAST SIG_NAME CPU0_BP0
J 0
(-1450 5610);
DISPLAY 0.489362 (-1450 5610);
WIRE 16 -1 (-675 5500)(-1475 5500);
FORCEPROP 2 LAST SIG_NAME CPU0_BP2
J 0
(-1450 5510);
DISPLAY 0.489362 (-1450 5510);
WIRE 16 -1 (-675 5450)(-1475 5450);
FORCEPROP 2 LAST SIG_NAME CPU0_BP3
J 0
(-1450 5460);
DISPLAY 0.489362 (-1450 5460);
WIRE 16 -1 (-675 5300)(-1475 5300);
FORCEPROP 2 LAST SIG_NAME CPU0_XTRIG_L5
J 0
(-1450 5310);
DISPLAY 0.489362 (-1450 5310);
WIRE 16 -1 (-675 5350)(-1475 5350);
FORCEPROP 2 LAST SIG_NAME CPU0_XTRIG_L4
J 0
(-1450 5360);
DISPLAY 0.489362 (-1450 5360);
WIRE 16 -1 (-675 5250)(-1475 5250);
FORCEPROP 2 LAST SIG_NAME CPU0_XTRIG_L6
J 0
(-1450 5260);
DISPLAY 0.489362 (-1450 5260);
WIRE 16 -1 (-675 5200)(-1475 5200);
FORCEPROP 2 LAST SIG_NAME CPU0_XTRIG_L7
J 0
(-1450 5210);
DISPLAY 0.489362 (-1450 5210);
WIRE 16 -1 (-675 5150)(-1475 5150);
FORCEPROP 2 LAST SIG_NAME CPU0_THERMTRIP_N
J 0
(-1450 5160);
DISPLAY 0.489362 (-1450 5160);
WIRE 16 -1 (-675 5100)(-1475 5100);
FORCEPROP 2 LAST SIG_NAME APML_CPU0_ALERT_N
J 0
(-1450 5110);
DISPLAY 0.489362 (-1450 5110);
DOT 1 (-7675 1475);
DOT 1 (-9050 3100);
DOT 1 (-9050 3050);
DOT 1 (-9050 3000);
DOT 1 (-9050 2950);
DOT 1 (-9050 2900);
DOT 1 (-7025 1475);
DOT 1 (-150 2800);
DOT 1 (-150 2900);
DOT 1 (-150 2850);
DOT 1 (-7675 1050);
DOT 1 (-9050 3150);
DOT 1 (-8675 4525);
DOT 1 (-5900 1775);
DOT 1 (-6700 2325);
DOT 1 (-6625 2275);
DOT 1 (-6550 2225);
DOT 1 (-6475 2175);
DOT 1 (-6350 2075);
DOT 1 (-6275 2025);
DOT 1 (-6200 1975);
DOT 1 (-6125 1925);
DOT 1 (-5975 1825);
DOT 1 (-8000 1100);
DOT 1 (-8000 1475);
DOT 1 (-7350 1000);
DOT 1 (-7350 1475);
DOT 1 (-7025 950);
DOT 1 (-6675 900);
DOT 1 (-6375 850);
DOT 1 (-6675 1475);
DOT 1 (-150 2225);
DOT 1 (-150 2175);
DOT 1 (-150 2275);
DOT 1 (-225 5600);
DOT 1 (-225 5550);
DOT 1 (-225 5500);
DOT 1 (-225 5450);
DOT 1 (-225 5350);
DOT 1 (-225 5400);
DOT 1 (-225 5300);
DOT 1 (-225 5250);
DOT 1 (-225 5200);
DOT 1 (-225 5150);
FORCENOTE
CAD NOTE: IF DEPOP R1533, PLEASE POP R536
(-2000 3675) 0;
DISPLAY LEFT (-2000 3675);
DISPLAY 1.021277 (-2000 3675);
QUIT
